FILE_TYPE = MACRO_DRAWING;
SET COLOR_WIRE YELLOW;
SET COLOR_PROP MONO;
SET COLOR_DOT WHITE;
SET COLOR_ARC YELLOW;
SET COLOR_BODY GREEN;
SET COLOR_NOTE MONO;
SET PROP_DISPLAY VALUE;
SET PAGE_NUMBER P236;
FORCEADD OFFPAGE..2
(11500 4450);
FORCEPROP 2 LAST $XR0 235 
J 0
(11689 4450);
DISPLAY 0.638298 (11689 4450);
PAINT MONO (11689 4450);
FORCEPROP 2 LAST PATH I1
J 0
(11700 4500);
DISPLAY 1.021277 (11700 4500);
PAINT ORANGE (11700 4500);
DISPLAY INVISIBLE (11700 4500);
FORCEPROP 2 LAST BOM_COST PROC_VRD_PVCCIO_CPU0
J 0
(11700 4500);
DISPLAY 2.340426 (11700 4500);
PAINT WHITE (11700 4500);
DISPLAY INVISIBLE (11700 4500);
FORCEPROP 2 LAST CDS_LIB mstr_standard
J 0
(11500 4450);
DISPLAY 1.617021 (11500 4450);
PAINT ORANGE (11500 4450);
DISPLAY INVISIBLE (11500 4450);
FORCEPROP 2 LAST ROOM PVCCIO_CPU0
J 0
(11100 4525);
DISPLAY 3.127660 (11100 4525);
PAINT WHITE (11100 4525);
DISPLAY INVISIBLE (11100 4525);
FORCEPROP 1 LAST OFFPAGE TRUE
J 0
(11825 4325);
PAINT GREEN (11825 4325);
DISPLAY INVISIBLE (11825 4325);
FORCEPROP 1 LAST COMMENT_BODY TRUE
J 0
(11455 4355);
DISPLAY 2.787234 (11455 4355);
PAINT PEACH (11455 4355);
DISPLAY INVISIBLE (11455 4355);
FORCEADD GND..1
(10450 3600);
FORCEPROP 3 LASTPIN (10450 3650) SIG_NAME GND\g
J 0
(10460 3660);
DISPLAY 0.659574 (10460 3660);
PAINT MONO (10460 3660);
DISPLAY INVISIBLE (10460 3660);
FORCEPROP 1 LAST SIZE 1B
J 0
(10525 3550);
DISPLAY 2.787234 (10525 3550);
PAINT GREEN (10525 3550);
DISPLAY INVISIBLE (10525 3550);
FORCEPROP 2 LAST CDS_LIB mstr_symbols
J 0
(10450 3600);
DISPLAY 1.617021 (10450 3600);
PAINT ORANGE (10450 3600);
DISPLAY INVISIBLE (10450 3600);
FORCEPROP 1 LAST PATH I11
J 0
(10525 3600);
DISPLAY 0.872340 (10525 3600);
PAINT AQUA (10525 3600);
DISPLAY INVISIBLE (10525 3600);
FORCEPROP 1 LAST VOLTAGE 0.0V
J 0
(10405 3557);
DISPLAY 0.340426 (10405 3557);
PAINT SKYBLUE (10405 3557);
DISPLAY INVISIBLE (10405 3557);
FORCEPROP 2 LAST BOM_COST PROC_VRD_PVCCIO_CPU0
J 0
(10075 3675);
DISPLAY 2.340426 (10075 3675);
PAINT WHITE (10075 3675);
DISPLAY INVISIBLE (10075 3675);
FORCEPROP 2 LAST ROOM PVCCIO_CPU0
J 0
(9900 3675);
DISPLAY 3.127660 (9900 3675);
PAINT WHITE (9900 3675);
DISPLAY INVISIBLE (9900 3675);
FORCEPROP 1 LAST BODY_TYPE PLUMBING
J 0
(10405 3557);
DISPLAY 0.340426 (10405 3557);
PAINT GREEN (10405 3557);
DISPLAY INVISIBLE (10405 3557);
FORCEPROP 1 LAST HDL_POWER GND
J 0
(10450 3750);
DISPLAY 2.787234 (10450 3750);
PAINT GREEN (10450 3750);
DISPLAY INVISIBLE (10450 3750);
FORCEADD IR354XX..1
(9850 4275);
FORCEPROP 2 LASTPIN (10350 4575) $PN 31
J 0
(10360 4585);
DISPLAY 0.617021 (10360 4585);
PAINT ORANGE (10360 4585);
FORCEPROP 2 LASTPIN (10350 4625) $PN 37
J 0
(10360 4635);
DISPLAY 0.617021 (10360 4635);
PAINT ORANGE (10360 4635);
FORCEPROP 2 LASTPIN (10350 3725) $PN 5
J 0
(10360 3735);
DISPLAY 0.617021 (10360 3735);
PAINT ORANGE (10360 3735);
FORCEPROP 2 LASTPIN (10350 3775) $PN 7
J 0
(10360 3785);
DISPLAY 0.617021 (10360 3785);
PAINT ORANGE (10360 3785);
FORCEPROP 2 LASTPIN (9350 4275) $PN 6
J 2
(9340 4285);
DISPLAY 0.617021 (9340 4285);
PAINT ORANGE (9340 4285);
FORCEPROP 2 LASTPIN (9350 4525) $PN 35
J 2
(9340 4535);
DISPLAY 0.617021 (9340 4535);
PAINT ORANGE (9340 4535);
FORCEPROP 2 LASTPIN (9350 4425) $PN 1
J 2
(9340 4435);
DISPLAY 0.617021 (9340 4435);
PAINT ORANGE (9340 4435);
FORCEPROP 2 LASTPIN (9350 4825) $PN 3
J 2
(9340 4835);
DISPLAY 0.617021 (9340 4835);
PAINT ORANGE (9340 4835);
FORCEPROP 2 LASTPIN (9350 4725) $PN 25
J 2
(9340 4735);
DISPLAY 0.617021 (9340 4735);
PAINT ORANGE (9340 4735);
FORCEPROP 2 LASTPIN (9350 4775) $PN 30
J 2
(9340 4785);
DISPLAY 0.617021 (9340 4785);
PAINT ORANGE (9340 4785);
FORCEPROP 1 LAST LOCATION EU7A3
J 0
(9400 5075);
DISPLAY 0.617021 (9400 5075);
PAINT AQUA (9400 5075);
FORCEPROP 1 LAST MATERIAL IC
J 0
(9400 5025);
DISPLAY 0.617021 (9400 5025);
PAINT SKYBLUE (9400 5025);
FORCEPROP 2 LAST NO_XNET_CONNECTION 1
J 0
(9400 5125);
PAINT MONO (9400 5125);
FORCEPROP 2 LASTPIN (10350 4825) $PN 38
J 0
(10360 4835);
DISPLAY 0.617021 (10360 4835);
PAINT ORANGE (10360 4835);
FORCEPROP 2 LASTPIN (10350 3825) $PN 40
J 0
(10360 3835);
DISPLAY 0.617021 (10360 3835);
PAINT ORANGE (10360 3835);
FORCEPROP 2 LASTPIN (10350 3875) $PN 2
J 0
(10360 3885);
DISPLAY 0.617021 (10360 3885);
PAINT ORANGE (10360 3885);
FORCEPROP 2 LASTPIN (10350 3975) $PN 10
J 0
(10360 3985);
DISPLAY 0.617021 (10360 3985);
PAINT ORANGE (10360 3985);
FORCEPROP 2 LASTPIN (9350 4175) $PN 34
J 2
(9340 4185);
DISPLAY 0.617021 (9340 4185);
PAINT ORANGE (9340 4185);
FORCEPROP 2 LASTPIN (10350 4325) $PN 36
J 0
(10360 4335);
DISPLAY 0.617021 (10360 4335);
PAINT ORANGE (10360 4335);
FORCEPROP 2 LASTPIN (9350 4325) $PN 41
J 2
(9340 4335);
DISPLAY 0.617021 (9340 4335);
PAINT ORANGE (9340 4335);
FORCEPROP 2 LASTPIN (9350 4625) $PN 4
J 2
(9340 4635);
DISPLAY 0.617021 (9340 4635);
PAINT ORANGE (9340 4635);
FORCEPROP 1 LAST PART_NUMBER H73684-001
J 0
(9500 3600);
DISPLAY 0.617021 (9500 3600);
PAINT BLUE (9500 3600);
FORCEPROP 2 LASTPIN (9350 3975) $PN 33
J 2
(9340 3985);
DISPLAY 0.617021 (9340 3985);
PAINT ORANGE (9340 3985);
FORCEPROP 2 LASTPIN (9350 3925) $PN 32
J 2
(9340 3935);
DISPLAY 0.617021 (9340 3935);
PAINT ORANGE (9340 3935);
FORCEPROP 2 LASTPIN (9350 4075) $PN 39
J 2
(9340 4085);
DISPLAY 0.617021 (9340 4085);
PAINT ORANGE (9340 4085);
FORCEPROP 2 LAST CDS_LIB mstr_discrete
J 0
(9850 4275);
PAINT ORANGE (9850 4275);
DISPLAY INVISIBLE (9850 4275);
FORCEPROP 2 LAST CDS_LOCATION EU7A3
J 0
(9400 5075);
DISPLAY 0.617021 (9400 5075);
PAINT AQUA (9400 5075);
DISPLAY INVISIBLE (9400 5075);
FORCEPROP 1 LAST PATH I116
J 0
(9850 5025);
PAINT GREEN (9850 5025);
DISPLAY INVISIBLE (9850 5025);
FORCEPROP 1 LAST PACK_TYPE SM
J 0
(9400 5125);
PAINT SKYBLUE (9400 5125);
DISPLAY INVISIBLE (9400 5125);
FORCEPROP 2 LAST SEC_TYPE SM
J 0
(9400 5125);
DISPLAY 1.021277 (9400 5125);
PAINT ORANGE (9400 5125);
DISPLAY INVISIBLE (9400 5125);
FORCEPROP 2 LAST SEC 1
J 0
(9400 5125);
DISPLAY 0.680851 (9400 5125);
PAINT MONO (9400 5125);
DISPLAY INVISIBLE (9400 5125);
FORCEPROP 1 LAST VALUE IR35412
J 1
(9850 4900);
DISPLAY 0.617021 (9850 4900);
PAINT SKYBLUE (9850 4900);
DISPLAY INVISIBLE (9850 4900);
FORCEADD IR354XX..1
(9875 2525);
FORCEPROP 2 LASTPIN (10375 3075) $PN 38
J 0
(10385 3085);
DISPLAY 0.617021 (10385 3085);
PAINT ORANGE (10385 3085);
FORCEPROP 2 LASTPIN (10375 2025) $PN 7
J 0
(10385 2035);
DISPLAY 0.617021 (10385 2035);
PAINT ORANGE (10385 2035);
FORCEPROP 2 LAST NO_XNET_CONNECTION 1
J 0
(9425 3375);
PAINT MONO (9425 3375);
FORCEPROP 1 LAST MATERIAL IC
J 0
(9425 3275);
DISPLAY 0.617021 (9425 3275);
PAINT SKYBLUE (9425 3275);
FORCEPROP 2 LASTPIN (9375 3025) $PN 30
J 2
(9365 3035);
DISPLAY 0.617021 (9365 3035);
PAINT ORANGE (9365 3035);
FORCEPROP 2 LASTPIN (9375 2975) $PN 25
J 2
(9365 2985);
DISPLAY 0.617021 (9365 2985);
PAINT ORANGE (9365 2985);
FORCEPROP 2 LASTPIN (9375 2675) $PN 1
J 2
(9365 2685);
DISPLAY 0.617021 (9365 2685);
PAINT ORANGE (9365 2685);
FORCEPROP 2 LASTPIN (9375 2225) $PN 33
J 2
(9365 2235);
DISPLAY 0.617021 (9365 2235);
PAINT ORANGE (9365 2235);
FORCEPROP 2 LASTPIN (9375 2525) $PN 6
J 2
(9365 2535);
DISPLAY 0.617021 (9365 2535);
PAINT ORANGE (9365 2535);
FORCEPROP 2 LASTPIN (9375 2175) $PN 32
J 2
(9365 2185);
DISPLAY 0.617021 (9365 2185);
PAINT ORANGE (9365 2185);
FORCEPROP 2 LASTPIN (9375 2425) $PN 34
J 2
(9365 2435);
DISPLAY 0.617021 (9365 2435);
PAINT ORANGE (9365 2435);
FORCEPROP 2 LASTPIN (9375 2325) $PN 39
J 2
(9365 2335);
DISPLAY 0.617021 (9365 2335);
PAINT ORANGE (9365 2335);
FORCEPROP 2 LASTPIN (10375 1975) $PN 5
J 0
(10385 1985);
DISPLAY 0.617021 (10385 1985);
PAINT ORANGE (10385 1985);
FORCEPROP 2 LASTPIN (10375 2225) $PN 10
J 0
(10385 2235);
DISPLAY 0.617021 (10385 2235);
PAINT ORANGE (10385 2235);
FORCEPROP 2 LASTPIN (10375 2125) $PN 2
J 0
(10385 2135);
DISPLAY 0.617021 (10385 2135);
PAINT ORANGE (10385 2135);
FORCEPROP 2 LASTPIN (9375 2775) $PN 35
J 2
(9365 2785);
DISPLAY 0.617021 (9365 2785);
PAINT ORANGE (9365 2785);
FORCEPROP 2 LASTPIN (10375 2075) $PN 40
J 0
(10385 2085);
DISPLAY 0.617021 (10385 2085);
PAINT ORANGE (10385 2085);
FORCEPROP 1 LAST LOCATION EU7A2
J 0
(9425 3325);
DISPLAY 0.617021 (9425 3325);
PAINT AQUA (9425 3325);
FORCEPROP 2 LASTPIN (9375 2875) $PN 4
J 2
(9365 2885);
DISPLAY 0.617021 (9365 2885);
PAINT ORANGE (9365 2885);
FORCEPROP 2 LASTPIN (9375 3075) $PN 3
J 2
(9365 3085);
DISPLAY 0.617021 (9365 3085);
PAINT ORANGE (9365 3085);
FORCEPROP 2 LASTPIN (10375 2825) $PN 31
J 0
(10385 2835);
DISPLAY 0.617021 (10385 2835);
PAINT ORANGE (10385 2835);
FORCEPROP 2 LASTPIN (10375 2575) $PN 36
J 0
(10385 2585);
DISPLAY 0.617021 (10385 2585);
PAINT ORANGE (10385 2585);
FORCEPROP 1 LAST PART_NUMBER H73684-001
J 0
(9500 1825);
DISPLAY 0.617021 (9500 1825);
PAINT BLUE (9500 1825);
FORCEPROP 2 LASTPIN (10375 2875) $PN 37
J 0
(10385 2885);
DISPLAY 0.617021 (10385 2885);
PAINT ORANGE (10385 2885);
FORCEPROP 2 LASTPIN (9375 2575) $PN 41
J 2
(9365 2585);
DISPLAY 0.617021 (9365 2585);
PAINT ORANGE (9365 2585);
FORCEPROP 1 LAST PATH I117
J 0
(9875 3275);
PAINT GREEN (9875 3275);
DISPLAY INVISIBLE (9875 3275);
FORCEPROP 2 LAST CDS_LOCATION EU7A2
J 0
(9425 3325);
DISPLAY 0.617021 (9425 3325);
PAINT AQUA (9425 3325);
DISPLAY INVISIBLE (9425 3325);
FORCEPROP 2 LAST SEC 1
J 0
(9425 3375);
DISPLAY 0.680851 (9425 3375);
PAINT MONO (9425 3375);
DISPLAY INVISIBLE (9425 3375);
FORCEPROP 2 LAST SEC_TYPE SM
J 0
(9425 3375);
DISPLAY 1.021277 (9425 3375);
PAINT ORANGE (9425 3375);
DISPLAY INVISIBLE (9425 3375);
FORCEPROP 1 LAST PACK_TYPE SM
J 0
(9425 3375);
PAINT SKYBLUE (9425 3375);
DISPLAY INVISIBLE (9425 3375);
FORCEPROP 2 LAST CDS_LIB mstr_discrete
J 0
(9875 2525);
PAINT ORANGE (9875 2525);
DISPLAY INVISIBLE (9875 2525);
FORCEPROP 1 LAST VALUE IR35412
J 1
(9875 3150);
DISPLAY 0.617021 (9875 3150);
PAINT SKYBLUE (9875 3150);
DISPLAY INVISIBLE (9875 3150);
FORCEADD RES..2
(12125 4450);
FORCEPROP 1 LAST WATTAGE 1/16W
J 0
(12165 4425);
DISPLAY 0.617021 (12165 4425);
PAINT SKYBLUE (12165 4425);
FORCEPROP 1 LAST MATERIAL EMPTY
J 0
(12165 4375);
DISPLAY 0.617021 (12165 4375);
PAINT RED (12165 4375);
FORCEPROP 1 LASTPIN (12125 4350) $PN 2
J 0
(12130 4360);
DISPLAY 0.787234 (12130 4360);
PAINT ORANGE (12130 4360);
FORCEPROP 1 LAST LOCATION R3L15
J 0
(12170 4575);
DISPLAY 0.617021 (12170 4575);
PAINT AQUA (12170 4575);
FORCEPROP 1 LAST VALUE 68.1K
J 0
(12170 4525);
DISPLAY 0.617021 (12170 4525);
PAINT SKYBLUE (12170 4525);
FORCEPROP 1 LAST TOLERANCE 1%
J 0
(12170 4475);
DISPLAY 0.617021 (12170 4475);
PAINT SKYBLUE (12170 4475);
FORCEPROP 1 LAST PACK_TYPE 0402
J 0
(12165 4275);
DISPLAY 0.617021 (12165 4275);
PAINT SKYBLUE (12165 4275);
FORCEPROP 1 LASTPIN (12125 4550) $PN 1
J 0
(12130 4512);
DISPLAY 0.787234 (12130 4512);
PAINT ORANGE (12130 4512);
FORCEPROP 1 LAST PART_NUMBER G21796-187
J 0
(12165 4325);
DISPLAY 0.617021 (12165 4325);
PAINT BLUE (12165 4325);
FORCEPROP 2 LAST CDS_LIB mstr_discrete
J 0
(12125 4450);
PAINT ORANGE (12125 4450);
DISPLAY INVISIBLE (12125 4450);
FORCEPROP 1 LAST PATH I118
J 0
(12175 4625);
DISPLAY 0.978723 (12175 4625);
PAINT WHITE (12175 4625);
DISPLAY INVISIBLE (12175 4625);
FORCEPROP 2 LAST SEC 1
J 0
(12175 4675);
PAINT MONO (12175 4675);
DISPLAY INVISIBLE (12175 4675);
FORCEPROP 2 LAST SEC_TYPE 0402
J 0
(12175 4675);
DISPLAY 1.021277 (12175 4675);
PAINT ORANGE (12175 4675);
DISPLAY INVISIBLE (12175 4675);
FORCEADD GND..1
(12125 4200);
FORCEPROP 3 LASTPIN (12125 4250) SIG_NAME GND\g
J 0
(12135 4260);
DISPLAY 0.659574 (12135 4260);
PAINT MONO (12135 4260);
DISPLAY INVISIBLE (12135 4260);
FORCEPROP 2 LAST BOM_COST PROC_VRD_VCCIN_CPU0
J 0
(11750 4275);
DISPLAY 1.446809 (11750 4275);
PAINT MONO (11750 4275);
DISPLAY INVISIBLE (11750 4275);
FORCEPROP 2 LAST ROOM PVSA_CPU1_PWR_VR
J 0
(11575 4275);
DISPLAY 1.936170 (11575 4275);
PAINT ORANGE (11575 4275);
DISPLAY INVISIBLE (11575 4275);
FORCEPROP 1 LAST VOLTAGE 0
J 0
(12125 4200);
PAINT SKYBLUE (12125 4200);
DISPLAY INVISIBLE (12125 4200);
FORCEPROP 2 LAST CDS_LIB mstr_symbols
J 0
(12125 4200);
PAINT ORANGE (12125 4200);
DISPLAY INVISIBLE (12125 4200);
FORCEPROP 1 LAST SIZE 1B
J 0
(12200 4150);
DISPLAY 1.723404 (12200 4150);
PAINT GREEN (12200 4150);
DISPLAY INVISIBLE (12200 4150);
FORCEPROP 1 LAST PATH I119
J 0
(12200 4200);
DISPLAY 0.872340 (12200 4200);
PAINT AQUA (12200 4200);
DISPLAY INVISIBLE (12200 4200);
FORCEPROP 1 LAST BODY_TYPE PLUMBING
J 0
(12080 4157);
DISPLAY 0.340426 (12080 4157);
PAINT GREEN (12080 4157);
DISPLAY INVISIBLE (12080 4157);
FORCEPROP 1 LAST HDL_POWER GND
J 0
(12125 4350);
DISPLAY 1.723404 (12125 4350);
PAINT GREEN (12125 4350);
DISPLAY INVISIBLE (12125 4350);
FORCEADD RES..2
(12150 2700);
FORCEPROP 1 LAST TOLERANCE 1%
J 0
(12195 2725);
DISPLAY 0.617021 (12195 2725);
PAINT SKYBLUE (12195 2725);
FORCEPROP 1 LASTPIN (12150 2800) $PN 1
J 0
(12155 2762);
DISPLAY 0.787234 (12155 2762);
PAINT ORANGE (12155 2762);
FORCEPROP 1 LASTPIN (12150 2600) $PN 2
J 0
(12155 2610);
DISPLAY 0.787234 (12155 2610);
PAINT ORANGE (12155 2610);
FORCEPROP 1 LAST LOCATION R3L14
J 0
(12195 2825);
DISPLAY 0.617021 (12195 2825);
PAINT AQUA (12195 2825);
FORCEPROP 1 LAST VALUE 68.1K
J 0
(12195 2775);
DISPLAY 0.617021 (12195 2775);
PAINT SKYBLUE (12195 2775);
FORCEPROP 1 LAST WATTAGE 1/16W
J 0
(12190 2675);
DISPLAY 0.617021 (12190 2675);
PAINT SKYBLUE (12190 2675);
FORCEPROP 1 LAST MATERIAL EMPTY
J 0
(12190 2625);
DISPLAY 0.617021 (12190 2625);
PAINT RED (12190 2625);
FORCEPROP 1 LAST PART_NUMBER G21796-187
J 0
(12190 2575);
DISPLAY 0.617021 (12190 2575);
PAINT BLUE (12190 2575);
FORCEPROP 1 LAST PACK_TYPE 0402
J 0
(12190 2525);
DISPLAY 0.617021 (12190 2525);
PAINT SKYBLUE (12190 2525);
FORCEPROP 2 LAST CDS_LIB mstr_discrete
J 0
(12150 2700);
PAINT ORANGE (12150 2700);
DISPLAY INVISIBLE (12150 2700);
FORCEPROP 1 LAST PATH I120
J 0
(12200 2875);
DISPLAY 0.978723 (12200 2875);
PAINT WHITE (12200 2875);
DISPLAY INVISIBLE (12200 2875);
FORCEPROP 2 LAST SEC 1
J 0
(12200 2925);
PAINT MONO (12200 2925);
DISPLAY INVISIBLE (12200 2925);
FORCEPROP 2 LAST SEC_TYPE 0402
J 0
(12200 2925);
DISPLAY 1.021277 (12200 2925);
PAINT ORANGE (12200 2925);
DISPLAY INVISIBLE (12200 2925);
FORCEADD GND..1
(12150 2450);
FORCEPROP 3 LASTPIN (12150 2500) SIG_NAME GND\g
J 0
(12160 2510);
DISPLAY 0.659574 (12160 2510);
PAINT MONO (12160 2510);
DISPLAY INVISIBLE (12160 2510);
FORCEPROP 2 LAST BOM_COST PROC_VRD_VCCIN_CPU0
J 0
(11775 2525);
DISPLAY 1.446809 (11775 2525);
PAINT MONO (11775 2525);
DISPLAY INVISIBLE (11775 2525);
FORCEPROP 2 LAST ROOM PVSA_CPU1_PWR_VR
J 0
(11600 2525);
DISPLAY 1.936170 (11600 2525);
PAINT ORANGE (11600 2525);
DISPLAY INVISIBLE (11600 2525);
FORCEPROP 1 LAST VOLTAGE 0
J 0
(12150 2450);
PAINT SKYBLUE (12150 2450);
DISPLAY INVISIBLE (12150 2450);
FORCEPROP 2 LAST CDS_LIB mstr_symbols
J 0
(12150 2450);
PAINT ORANGE (12150 2450);
DISPLAY INVISIBLE (12150 2450);
FORCEPROP 1 LAST PATH I121
J 0
(12225 2450);
DISPLAY 0.872340 (12225 2450);
PAINT AQUA (12225 2450);
DISPLAY INVISIBLE (12225 2450);
FORCEPROP 1 LAST SIZE 1B
J 0
(12225 2400);
DISPLAY 1.723404 (12225 2400);
PAINT GREEN (12225 2400);
DISPLAY INVISIBLE (12225 2400);
FORCEPROP 1 LAST BODY_TYPE PLUMBING
J 0
(12105 2407);
DISPLAY 0.340426 (12105 2407);
PAINT GREEN (12105 2407);
DISPLAY INVISIBLE (12105 2407);
FORCEPROP 1 LAST HDL_POWER GND
J 0
(12150 2600);
DISPLAY 1.723404 (12150 2600);
PAINT GREEN (12150 2600);
DISPLAY INVISIBLE (12150 2600);
FORCEADD P5V_STBY..1
(8525 5150);
FORCEPROP 3 LASTPIN (8525 5100) SIG_NAME P5V_STBY\g
J 0
(8535 5110);
DISPLAY 0.659574 (8535 5110);
PAINT MONO (8535 5110);
DISPLAY INVISIBLE (8535 5110);
FORCEPROP 1 LAST VOLTAGE 5.0V
J 0
(8480 5107);
DISPLAY 0.340426 (8480 5107);
PAINT SKYBLUE (8480 5107);
DISPLAY INVISIBLE (8480 5107);
FORCEPROP 1 LAST SIZE 1B
J 0
(8570 5172);
DISPLAY 0.340426 (8570 5172);
PAINT GREEN (8570 5172);
DISPLAY INVISIBLE (8570 5172);
FORCEPROP 2 LAST CDS_LIB mstr_symbols
J 0
(8525 5150);
PAINT ORANGE (8525 5150);
DISPLAY INVISIBLE (8525 5150);
FORCEPROP 1 LAST PATH I122
J 0
(8570 5152);
DISPLAY 0.340426 (8570 5152);
PAINT GREEN (8570 5152);
DISPLAY INVISIBLE (8570 5152);
FORCEPROP 1 LAST BODY_TYPE PLUMBING
J 0
(8480 5107);
DISPLAY 0.340426 (8480 5107);
PAINT GREEN (8480 5107);
DISPLAY INVISIBLE (8480 5107);
FORCEPROP 1 LAST HDL_POWER P5V_STBY
J 0
(8225 5025);
DISPLAY 0.872340 (8225 5025);
PAINT ORANGE (8225 5025);
DISPLAY INVISIBLE (8225 5025);
FORCEADD CAP_A..1
(9125 2025);
FORCEPROP 1 LAST PACK_TYPE 0402V
J 0
(9175 1825);
DISPLAY 0.617021 (9175 1825);
PAINT SKYBLUE (9175 1825);
FORCEPROP 1 LAST VOLTAGE 16V
J 0
(9175 2025);
DISPLAY 0.617021 (9175 2025);
PAINT SKYBLUE (9175 2025);
FORCEPROP 1 LAST LOCATION CT67
J 0
(8975 2025);
DISPLAY 0.617021 (8975 2025);
PAINT AQUA (8975 2025);
FORCEPROP 0 LAST POP NOPOP
J 0
(8900 1875);
DISPLAY 1.021277 (8900 1875);
PAINT RED (8900 1875);
FORCEPROP 1 LAST TOLERANCE 10%
J 0
(9175 1975);
DISPLAY 0.617021 (9175 1975);
PAINT SKYBLUE (9175 1975);
FORCEPROP 1 LAST MATERIAL X7R
J 0
(9175 1925);
DISPLAY 0.617021 (9175 1925);
PAINT SKYBLUE (9175 1925);
FORCEPROP 1 LAST PART_NUMBER A36096-030
J 0
(9175 1875);
DISPLAY 0.617021 (9175 1875);
PAINT BLUE (9175 1875);
FORCEPROP 1 LAST VALUE 0.1UF
J 0
(9175 2075);
DISPLAY 0.617021 (9175 2075);
PAINT SKYBLUE (9175 2075);
FORCEPROP 1 LASTPIN (9125 1925) $PN 2
J 0
(9135 1905);
DISPLAY 0.787234 (9135 1905);
PAINT ORANGE (9135 1905);
DISPLAY INVISIBLE (9135 1905);
FORCEPROP 1 LASTPIN (9125 2125) $PN 1
J 0
(9135 2105);
DISPLAY 0.787234 (9135 2105);
PAINT ORANGE (9135 2105);
DISPLAY INVISIBLE (9135 2105);
FORCEPROP 2 LAST ROOM PVCCIN_CPU0_PWR_VR
J 0
(9175 2175);
DISPLAY 1.361702 (9175 2175);
PAINT ORANGE (9175 2175);
DISPLAY INVISIBLE (9175 2175);
FORCEPROP 1 LAST PATH I124
J 0
(9175 2175);
DISPLAY 0.978723 (9175 2175);
PAINT WHITE (9175 2175);
DISPLAY INVISIBLE (9175 2175);
FORCEPROP 2 LAST CDS_LIB dev_discrete
J 0
(9125 2025);
PAINT MONO (9125 2025);
DISPLAY INVISIBLE (9125 2025);
FORCEADD GND..1
(9125 1775);
FORCEPROP 3 LASTPIN (9125 1825) SIG_NAME GND\g
J 0
(9135 1835);
DISPLAY 0.659574 (9135 1835);
PAINT MONO (9135 1835);
DISPLAY INVISIBLE (9135 1835);
FORCEPROP 2 LAST ROOM PVCCIN_CPU0_PWR_VR
J 0
(8575 1850);
DISPLAY 1.936170 (8575 1850);
PAINT ORANGE (8575 1850);
DISPLAY INVISIBLE (8575 1850);
FORCEPROP 2 LAST BOM_COST PROC_VRD_VCCIN_CPU0
J 0
(8750 1850);
DISPLAY 1.446809 (8750 1850);
PAINT MONO (8750 1850);
DISPLAY INVISIBLE (8750 1850);
FORCEPROP 1 LAST SIZE 1B
J 0
(9200 1725);
DISPLAY 1.723404 (9200 1725);
PAINT GREEN (9200 1725);
DISPLAY INVISIBLE (9200 1725);
FORCEPROP 1 LAST VOLTAGE 0
J 0
(9125 1775);
PAINT SKYBLUE (9125 1775);
DISPLAY INVISIBLE (9125 1775);
FORCEPROP 1 LAST PATH I125
J 0
(9200 1775);
DISPLAY 0.872340 (9200 1775);
PAINT AQUA (9200 1775);
DISPLAY INVISIBLE (9200 1775);
FORCEPROP 2 LAST CDS_LIB mstr_symbols
J 0
(9125 1775);
PAINT MONO (9125 1775);
DISPLAY INVISIBLE (9125 1775);
FORCEPROP 1 LAST BODY_TYPE PLUMBING
J 0
(9080 1732);
DISPLAY 0.340426 (9080 1732);
PAINT GREEN (9080 1732);
DISPLAY INVISIBLE (9080 1732);
FORCEPROP 1 LAST HDL_POWER GND
J 0
(9125 1925);
DISPLAY 1.723404 (9125 1925);
PAINT GREEN (9125 1925);
DISPLAY INVISIBLE (9125 1925);
FORCEADD GND..1
(9125 3500);
FORCEPROP 3 LASTPIN (9125 3550) SIG_NAME GND\g
J 0
(9135 3560);
DISPLAY 0.659574 (9135 3560);
PAINT MONO (9135 3560);
DISPLAY INVISIBLE (9135 3560);
FORCEPROP 1 LAST VOLTAGE 0
J 0
(9125 3500);
PAINT SKYBLUE (9125 3500);
DISPLAY INVISIBLE (9125 3500);
FORCEPROP 1 LAST SIZE 1B
J 0
(9200 3450);
DISPLAY 1.723404 (9200 3450);
PAINT GREEN (9200 3450);
DISPLAY INVISIBLE (9200 3450);
FORCEPROP 2 LAST BOM_COST PROC_VRD_VCCIN_CPU0
J 0
(8750 3575);
DISPLAY 1.446809 (8750 3575);
PAINT MONO (8750 3575);
DISPLAY INVISIBLE (8750 3575);
FORCEPROP 2 LAST ROOM PVCCIN_CPU0_PWR_VR
J 0
(8575 3575);
DISPLAY 1.936170 (8575 3575);
PAINT ORANGE (8575 3575);
DISPLAY INVISIBLE (8575 3575);
FORCEPROP 1 LAST PATH I126
J 0
(9200 3500);
DISPLAY 0.872340 (9200 3500);
PAINT AQUA (9200 3500);
DISPLAY INVISIBLE (9200 3500);
FORCEPROP 2 LAST CDS_LIB mstr_symbols
J 0
(9125 3500);
PAINT MONO (9125 3500);
DISPLAY INVISIBLE (9125 3500);
FORCEPROP 1 LAST BODY_TYPE PLUMBING
J 0
(9080 3457);
DISPLAY 0.340426 (9080 3457);
PAINT GREEN (9080 3457);
DISPLAY INVISIBLE (9080 3457);
FORCEPROP 1 LAST HDL_POWER GND
J 0
(9125 3650);
DISPLAY 1.723404 (9125 3650);
PAINT GREEN (9125 3650);
DISPLAY INVISIBLE (9125 3650);
FORCEADD CAP_A..1
(9125 3775);
FORCEPROP 1 LAST VALUE 0.1UF
J 0
(9175 3825);
DISPLAY 0.617021 (9175 3825);
PAINT SKYBLUE (9175 3825);
FORCEPROP 1 LAST VOLTAGE 16V
J 0
(9175 3775);
DISPLAY 0.617021 (9175 3775);
PAINT SKYBLUE (9175 3775);
FORCEPROP 0 LAST POP NOPOP
J 0
(8875 3600);
DISPLAY 1.021277 (8875 3600);
PAINT RED (8875 3600);
FORCEPROP 1 LASTPIN (9125 3675) $PN 2
J 0
(9135 3655);
DISPLAY 0.787234 (9135 3655);
PAINT ORANGE (9135 3655);
FORCEPROP 1 LASTPIN (9125 3875) $PN 1
J 0
(9135 3855);
DISPLAY 0.787234 (9135 3855);
PAINT ORANGE (9135 3855);
FORCEPROP 1 LAST PACK_TYPE 0402V
J 0
(9175 3575);
DISPLAY 0.617021 (9175 3575);
PAINT SKYBLUE (9175 3575);
FORCEPROP 1 LAST PART_NUMBER A36096-030
J 0
(9175 3625);
DISPLAY 0.617021 (9175 3625);
PAINT BLUE (9175 3625);
FORCEPROP 1 LAST MATERIAL X7R
J 0
(9175 3675);
DISPLAY 0.617021 (9175 3675);
PAINT SKYBLUE (9175 3675);
FORCEPROP 1 LAST TOLERANCE 10%
J 0
(9175 3725);
DISPLAY 0.617021 (9175 3725);
PAINT SKYBLUE (9175 3725);
FORCEPROP 1 LAST LOCATION CT66
J 0
(8975 3775);
DISPLAY 0.617021 (8975 3775);
PAINT AQUA (8975 3775);
FORCEPROP 2 LAST ROOM PVCCIN_CPU0_PWR_VR
J 0
(9175 3925);
DISPLAY 1.361702 (9175 3925);
PAINT ORANGE (9175 3925);
DISPLAY INVISIBLE (9175 3925);
FORCEPROP 1 LAST PATH I127
J 0
(9175 3925);
DISPLAY 0.978723 (9175 3925);
PAINT WHITE (9175 3925);
DISPLAY INVISIBLE (9175 3925);
FORCEPROP 2 LAST CDS_LIB dev_discrete
J 0
(9125 3775);
PAINT MONO (9125 3775);
DISPLAY INVISIBLE (9125 3775);
FORCEPROP 0 LAST SEC 1
J 0
(9175 3875);
DISPLAY 0.680851 (9175 3875);
PAINT MONO (9175 3875);
DISPLAY INVISIBLE (9175 3875);
FORCEPROP 2 LAST SEC_TYPE 0402V
J 0
(9175 3975);
DISPLAY 1.021277 (9175 3975);
PAINT ORANGE (9175 3975);
DISPLAY INVISIBLE (9175 3975);
FORCEADD GND..1
(10925 4100);
FORCEPROP 3 LASTPIN (10925 4150) SIG_NAME GND\g
J 0
(10935 4160);
DISPLAY 0.659574 (10935 4160);
PAINT MONO (10935 4160);
DISPLAY INVISIBLE (10935 4160);
FORCEPROP 1 LAST HDL_POWER GND
J 0
(10925 4250);
DISPLAY 1.170213 (10925 4250);
PAINT GREEN (10925 4250);
DISPLAY INVISIBLE (10925 4250);
FORCEPROP 1 LAST BODY_TYPE PLUMBING
J 0
(10880 4057);
DISPLAY 0.340426 (10880 4057);
PAINT GREEN (10880 4057);
DISPLAY INVISIBLE (10880 4057);
FORCEPROP 2 LAST ROOM VDDQ_KLM_PWR_VR
J 0
(10350 4175);
DISPLAY 1.361702 (10350 4175);
PAINT ORANGE (10350 4175);
DISPLAY INVISIBLE (10350 4175);
FORCEPROP 1 LAST VOLTAGE 0
J 0
(10925 4100);
PAINT SKYBLUE (10925 4100);
DISPLAY INVISIBLE (10925 4100);
FORCEPROP 1 LAST SIZE 1B
J 0
(11000 4050);
DISPLAY 1.170213 (11000 4050);
PAINT AQUA (11000 4050);
DISPLAY INVISIBLE (11000 4050);
FORCEPROP 1 LAST PATH I130
J 0
(11000 4100);
DISPLAY 0.872340 (11000 4100);
PAINT AQUA (11000 4100);
DISPLAY INVISIBLE (11000 4100);
FORCEPROP 2 LAST CDS_LIB mstr_symbols
J 0
(10925 4100);
PAINT MONO (10925 4100);
DISPLAY INVISIBLE (10925 4100);
FORCEADD GND..1
(10550 3375);
FORCEPROP 3 LASTPIN (10550 3425) SIG_NAME GND\g
J 0
(10560 3435);
DISPLAY 0.659574 (10560 3435);
PAINT MONO (10560 3435);
DISPLAY INVISIBLE (10560 3435);
FORCEPROP 1 LAST HDL_POWER GND
J 0
(10550 3525);
DISPLAY 1.723404 (10550 3525);
PAINT GREEN (10550 3525);
DISPLAY INVISIBLE (10550 3525);
FORCEPROP 1 LAST BODY_TYPE PLUMBING
J 0
(10505 3332);
DISPLAY 0.340426 (10505 3332);
PAINT GREEN (10505 3332);
DISPLAY INVISIBLE (10505 3332);
FORCEPROP 2 LAST ROOM PVCCIN_CPU0_PWR_VR
J 0
(10000 3450);
DISPLAY 1.936170 (10000 3450);
PAINT ORANGE (10000 3450);
DISPLAY INVISIBLE (10000 3450);
FORCEPROP 2 LAST BOM_COST PROC_VRD_VCCIN_CPU0
J 0
(10175 3450);
DISPLAY 1.446809 (10175 3450);
PAINT MONO (10175 3450);
DISPLAY INVISIBLE (10175 3450);
FORCEPROP 1 LAST VOLTAGE 0
J 0
(10550 3375);
PAINT SKYBLUE (10550 3375);
DISPLAY INVISIBLE (10550 3375);
FORCEPROP 1 LAST SIZE 1B
J 0
(10625 3325);
DISPLAY 1.723404 (10625 3325);
PAINT GREEN (10625 3325);
DISPLAY INVISIBLE (10625 3325);
FORCEPROP 1 LAST PATH I133
J 0
(10625 3375);
DISPLAY 0.872340 (10625 3375);
PAINT AQUA (10625 3375);
DISPLAY INVISIBLE (10625 3375);
FORCEPROP 2 LAST CDS_LIB mstr_symbols
J 0
(10550 3375);
PAINT MONO (10550 3375);
DISPLAY INVISIBLE (10550 3375);
FORCEADD CAP..1
(10900 2600);
FORCEPROP 1 LASTPIN (10900 2700) $PN 1
J 0
(10910 2680);
DISPLAY 0.787234 (10910 2680);
PAINT ORANGE (10910 2680);
FORCEPROP 1 LASTPIN (10900 2500) $PN 2
J 0
(10910 2480);
DISPLAY 0.787234 (10910 2480);
PAINT ORANGE (10910 2480);
FORCEPROP 1 LAST LOCATION CT69
J 0
(10750 2600);
DISPLAY 0.617021 (10750 2600);
PAINT AQUA (10750 2600);
FORCEPROP 1 LAST PACK_TYPE 0402LF
J 0
(10950 2400);
DISPLAY 0.617021 (10950 2400);
PAINT SKYBLUE (10950 2400);
FORCEPROP 1 LAST PART_NUMBER A36096-046
J 0
(10950 2450);
DISPLAY 0.617021 (10950 2450);
PAINT BLUE (10950 2450);
FORCEPROP 1 LAST MATERIAL X7R
J 0
(10950 2500);
DISPLAY 0.617021 (10950 2500);
PAINT SKYBLUE (10950 2500);
FORCEPROP 1 LAST TOLERANCE 10%
J 0
(10950 2550);
DISPLAY 0.617021 (10950 2550);
PAINT SKYBLUE (10950 2550);
FORCEPROP 1 LAST VOLTAGE 50V
J 0
(10950 2600);
DISPLAY 0.617021 (10950 2600);
PAINT SKYBLUE (10950 2600);
FORCEPROP 1 LAST VALUE 1000PF
J 0
(10950 2650);
DISPLAY 0.617021 (10950 2650);
PAINT SKYBLUE (10950 2650);
FORCEPROP 0 LAST POP NOPOP
J 0
(10925 2675);
DISPLAY 1.021277 (10925 2675);
PAINT RED (10925 2675);
FORCEPROP 0 LAST ROOM VDDQ_KLM_PWR_VR
J 0
(10950 2800);
DISPLAY 1.021277 (10950 2800);
PAINT ORANGE (10950 2800);
DISPLAY INVISIBLE (10950 2800);
FORCEPROP 1 LAST PATH I134
J 0
(10950 2750);
DISPLAY 0.978723 (10950 2750);
PAINT WHITE (10950 2750);
DISPLAY INVISIBLE (10950 2750);
FORCEPROP 2 LAST CDS_LIB mstr_discrete
J 0
(10900 2600);
PAINT MONO (10900 2600);
DISPLAY INVISIBLE (10900 2600);
FORCEPROP 0 LAST SEC 1
J 0
(10925 2725);
DISPLAY 0.680851 (10925 2725);
PAINT MONO (10925 2725);
DISPLAY INVISIBLE (10925 2725);
FORCEPROP 2 LAST SEC_TYPE 0402LF
J 0
(10950 2800);
DISPLAY 1.021277 (10950 2800);
PAINT ORANGE (10950 2800);
DISPLAY INVISIBLE (10950 2800);
FORCEADD GND..1
(10900 2425);
FORCEPROP 3 LASTPIN (10900 2475) SIG_NAME GND\g
J 0
(10910 2485);
DISPLAY 0.659574 (10910 2485);
PAINT MONO (10910 2485);
DISPLAY INVISIBLE (10910 2485);
FORCEPROP 2 LAST ROOM VDDQ_KLM_PWR_VR
J 0
(10325 2500);
DISPLAY 1.361702 (10325 2500);
PAINT ORANGE (10325 2500);
DISPLAY INVISIBLE (10325 2500);
FORCEPROP 1 LAST VOLTAGE 0
J 0
(10900 2425);
PAINT SKYBLUE (10900 2425);
DISPLAY INVISIBLE (10900 2425);
FORCEPROP 1 LAST SIZE 1B
J 0
(10975 2375);
DISPLAY 1.170213 (10975 2375);
PAINT AQUA (10975 2375);
DISPLAY INVISIBLE (10975 2375);
FORCEPROP 1 LAST PATH I135
J 0
(10975 2425);
DISPLAY 0.872340 (10975 2425);
PAINT AQUA (10975 2425);
DISPLAY INVISIBLE (10975 2425);
FORCEPROP 2 LAST CDS_LIB mstr_symbols
J 0
(10900 2425);
PAINT MONO (10900 2425);
DISPLAY INVISIBLE (10900 2425);
FORCEPROP 1 LAST BODY_TYPE PLUMBING
J 0
(10855 2382);
DISPLAY 0.340426 (10855 2382);
PAINT GREEN (10855 2382);
DISPLAY INVISIBLE (10855 2382);
FORCEPROP 1 LAST HDL_POWER GND
J 0
(10900 2575);
DISPLAY 1.170213 (10900 2575);
PAINT GREEN (10900 2575);
DISPLAY INVISIBLE (10900 2575);
FORCEADD CAP..1
(10925 4300);
FORCEPROP 1 LAST PART_NUMBER A36096-046
J 0
(10975 4150);
DISPLAY 0.617021 (10975 4150);
PAINT BLUE (10975 4150);
FORCEPROP 0 LAST POP NOPOP
J 0
(11075 4275);
DISPLAY 1.021277 (11075 4275);
PAINT RED (11075 4275);
FORCEPROP 1 LAST VALUE 1000PF
J 0
(11100 4375);
DISPLAY 0.617021 (11100 4375);
PAINT SKYBLUE (11100 4375);
FORCEPROP 1 LAST VOLTAGE 50V
J 0
(10975 4300);
DISPLAY 0.617021 (10975 4300);
PAINT SKYBLUE (10975 4300);
FORCEPROP 1 LAST TOLERANCE 10%
J 0
(10975 4250);
DISPLAY 0.617021 (10975 4250);
PAINT SKYBLUE (10975 4250);
FORCEPROP 1 LAST MATERIAL X7R
J 0
(10975 4200);
DISPLAY 0.617021 (10975 4200);
PAINT SKYBLUE (10975 4200);
FORCEPROP 1 LASTPIN (10925 4200) $PN 2
J 0
(10935 4180);
DISPLAY 0.787234 (10935 4180);
PAINT ORANGE (10935 4180);
FORCEPROP 1 LAST PACK_TYPE 0402LF
J 0
(10975 4100);
DISPLAY 0.617021 (10975 4100);
PAINT SKYBLUE (10975 4100);
FORCEPROP 1 LAST LOCATION CT64
J 0
(10975 4375);
DISPLAY 0.617021 (10975 4375);
PAINT AQUA (10975 4375);
FORCEPROP 1 LASTPIN (10925 4400) $PN 1
J 0
(10935 4380);
DISPLAY 0.787234 (10935 4380);
PAINT ORANGE (10935 4380);
FORCEPROP 2 LAST CDS_LIB mstr_discrete
J 0
(10925 4300);
PAINT MONO (10925 4300);
DISPLAY INVISIBLE (10925 4300);
FORCEPROP 0 LAST ROOM VDDQ_KLM_PWR_VR
J 0
(10975 4500);
DISPLAY 1.021277 (10975 4500);
PAINT ORANGE (10975 4500);
DISPLAY INVISIBLE (10975 4500);
FORCEPROP 1 LAST PATH I136
J 0
(10975 4450);
DISPLAY 0.978723 (10975 4450);
PAINT WHITE (10975 4450);
DISPLAY INVISIBLE (10975 4450);
FORCEPROP 0 LAST SEC 1
J 0
(10975 4425);
DISPLAY 0.680851 (10975 4425);
PAINT MONO (10975 4425);
DISPLAY INVISIBLE (10975 4425);
FORCEPROP 2 LAST SEC_TYPE 0402LF
J 0
(10975 4500);
DISPLAY 1.021277 (10975 4500);
PAINT ORANGE (10975 4500);
DISPLAY INVISIBLE (10975 4500);
FORCEADD GND..1
(11050 1650);
FORCEPROP 3 LASTPIN (11050 1700) SIG_NAME GND\g
J 0
(11060 1710);
DISPLAY 0.659574 (11060 1710);
PAINT MONO (11060 1710);
DISPLAY INVISIBLE (11060 1710);
FORCEPROP 1 LAST HDL_POWER GND
J 0
(11050 1800);
DISPLAY 1.723404 (11050 1800);
PAINT GREEN (11050 1800);
DISPLAY INVISIBLE (11050 1800);
FORCEPROP 1 LAST BODY_TYPE PLUMBING
J 0
(11005 1607);
DISPLAY 0.340426 (11005 1607);
PAINT GREEN (11005 1607);
DISPLAY INVISIBLE (11005 1607);
FORCEPROP 2 LAST ROOM PVCCIN_CPU0_PWR_VR
J 0
(10500 1725);
DISPLAY 1.936170 (10500 1725);
PAINT ORANGE (10500 1725);
DISPLAY INVISIBLE (10500 1725);
FORCEPROP 2 LAST BOM_COST PROC_VRD_VCCIN_CPU0
J 0
(10675 1725);
DISPLAY 1.446809 (10675 1725);
PAINT MONO (10675 1725);
DISPLAY INVISIBLE (10675 1725);
FORCEPROP 1 LAST VOLTAGE 0
J 0
(11050 1650);
PAINT SKYBLUE (11050 1650);
DISPLAY INVISIBLE (11050 1650);
FORCEPROP 1 LAST SIZE 1B
J 0
(11125 1600);
DISPLAY 1.723404 (11125 1600);
PAINT GREEN (11125 1600);
DISPLAY INVISIBLE (11125 1600);
FORCEPROP 1 LAST PATH I139
J 0
(11125 1650);
DISPLAY 0.872340 (11125 1650);
PAINT AQUA (11125 1650);
DISPLAY INVISIBLE (11125 1650);
FORCEPROP 2 LAST CDS_LIB mstr_symbols
J 0
(11050 1650);
PAINT MONO (11050 1650);
DISPLAY INVISIBLE (11050 1650);
FORCEADD CAP..1
(10550 3850);
FORCEPROP 0 LAST POP NOPOP
J 0
(10850 3800);
DISPLAY 0.808511 (10850 3800);
PAINT RED (10850 3800);
FORCEPROP 1 LAST TOLERANCE 10%
J 0
(10875 3900);
DISPLAY 0.617021 (10875 3900);
PAINT SKYBLUE (10875 3900);
FORCEPROP 1 LASTPIN (10550 3950) $PN 1
J 0
(10560 3930);
DISPLAY 0.787234 (10560 3930);
PAINT ORANGE (10560 3930);
FORCEPROP 1 LASTPIN (10550 3750) $PN 2
J 0
(10560 3730);
DISPLAY 0.787234 (10560 3730);
PAINT ORANGE (10560 3730);
FORCEPROP 1 LAST LOCATION CT65
J 0
(10600 3900);
DISPLAY 0.617021 (10600 3900);
PAINT AQUA (10600 3900);
FORCEPROP 1 LAST VOLTAGE 50V
J 0
(10625 3850);
DISPLAY 0.617021 (10625 3850);
PAINT SKYBLUE (10625 3850);
FORCEPROP 1 LAST VALUE 1000PF
J 0
(10725 3900);
DISPLAY 0.617021 (10725 3900);
PAINT SKYBLUE (10725 3900);
FORCEPROP 1 LAST MATERIAL X7R
J 0
(10850 3850);
DISPLAY 0.617021 (10850 3850);
PAINT SKYBLUE (10850 3850);
FORCEPROP 1 LAST PACK_TYPE 0402LF
J 0
(10725 3850);
DISPLAY 0.617021 (10725 3850);
PAINT SKYBLUE (10725 3850);
FORCEPROP 1 LAST PART_NUMBER A36096-046
J 0
(10625 3800);
DISPLAY 0.617021 (10625 3800);
PAINT BLUE (10625 3800);
FORCEPROP 0 LAST ROOM VDDQ_KLM_PWR_VR
J 0
(10600 4050);
DISPLAY 1.021277 (10600 4050);
PAINT ORANGE (10600 4050);
DISPLAY INVISIBLE (10600 4050);
FORCEPROP 1 LAST PATH I149
J 0
(10600 4000);
DISPLAY 0.978723 (10600 4000);
PAINT WHITE (10600 4000);
DISPLAY INVISIBLE (10600 4000);
FORCEPROP 2 LAST CDS_LIB mstr_discrete
J 0
(10550 3850);
PAINT MONO (10550 3850);
DISPLAY INVISIBLE (10550 3850);
FORCEPROP 2 LAST SEC_TYPE 0402LF
J 0
(10600 4050);
DISPLAY 1.021277 (10600 4050);
PAINT ORANGE (10600 4050);
DISPLAY INVISIBLE (10600 4050);
FORCEPROP 0 LAST SEC 1
J 0
(10600 4000);
DISPLAY 0.680851 (10600 4000);
PAINT MONO (10600 4000);
DISPLAY INVISIBLE (10600 4000);
FORCEADD CAP..1
(11050 2150);
FORCEPROP 1 LAST PART_NUMBER A36096-046
J 0
(11100 2000);
DISPLAY 0.617021 (11100 2000);
PAINT BLUE (11100 2000);
FORCEPROP 1 LAST TOLERANCE 10%
J 0
(11100 2100);
DISPLAY 0.617021 (11100 2100);
PAINT SKYBLUE (11100 2100);
FORCEPROP 1 LAST PACK_TYPE 0402LF
J 0
(11200 2050);
DISPLAY 0.617021 (11200 2050);
PAINT SKYBLUE (11200 2050);
FORCEPROP 1 LASTPIN (11050 2050) $PN 2
J 0
(11060 2030);
DISPLAY 0.787234 (11060 2030);
PAINT ORANGE (11060 2030);
FORCEPROP 1 LASTPIN (11050 2250) $PN 1
J 0
(11060 2230);
DISPLAY 0.787234 (11060 2230);
PAINT ORANGE (11060 2230);
FORCEPROP 1 LAST LOCATION CT68
J 0
(11100 2250);
DISPLAY 0.617021 (11100 2250);
PAINT AQUA (11100 2250);
FORCEPROP 1 LAST VALUE 1000PF
J 0
(11100 2200);
DISPLAY 0.617021 (11100 2200);
PAINT SKYBLUE (11100 2200);
FORCEPROP 1 LAST VOLTAGE 50V
J 0
(11100 2150);
DISPLAY 0.617021 (11100 2150);
PAINT SKYBLUE (11100 2150);
FORCEPROP 1 LAST MATERIAL X7R
J 0
(11100 2050);
DISPLAY 0.617021 (11100 2050);
PAINT SKYBLUE (11100 2050);
FORCEPROP 0 LAST POP NOPOP
J 0
(10850 2175);
DISPLAY 0.808511 (10850 2175);
PAINT RED (10850 2175);
FORCEPROP 2 LAST CDS_LIB mstr_discrete
J 0
(11050 2150);
PAINT MONO (11050 2150);
DISPLAY INVISIBLE (11050 2150);
FORCEPROP 1 LAST PATH I150
J 0
(11100 2300);
DISPLAY 0.978723 (11100 2300);
PAINT WHITE (11100 2300);
DISPLAY INVISIBLE (11100 2300);
FORCEPROP 0 LAST ROOM VDDQ_KLM_PWR_VR
J 0
(11100 2350);
DISPLAY 1.021277 (11100 2350);
PAINT ORANGE (11100 2350);
DISPLAY INVISIBLE (11100 2350);
FORCEPROP 0 LAST SEC 1
J 0
(11100 2300);
DISPLAY 0.680851 (11100 2300);
PAINT MONO (11100 2300);
DISPLAY INVISIBLE (11100 2300);
FORCEPROP 2 LAST SEC_TYPE 0402LF
J 0
(11100 2350);
DISPLAY 1.021277 (11100 2350);
PAINT ORANGE (11100 2350);
DISPLAY INVISIBLE (11100 2350);
FORCEADD RES..1
(8025 4050);
FORCEPROP 1 LAST LOCATION RT44
J 0
(8125 4075);
DISPLAY 0.617021 (8125 4075);
PAINT AQUA (8125 4075);
FORCEPROP 1 LASTPIN (8125 4050) $PN 2
J 0
(8087 4062);
DISPLAY 0.787234 (8087 4062);
PAINT ORANGE (8087 4062);
FORCEPROP 1 LASTPIN (7925 4050) $PN 1
J 0
(7937 4062);
DISPLAY 0.787234 (7937 4062);
PAINT ORANGE (7937 4062);
FORCEPROP 1 LAST VALUE 0
J 2
(7975 4000);
DISPLAY 0.617021 (7975 4000);
PAINT SKYBLUE (7975 4000);
FORCEPROP 1 LAST WATTAGE 1/10W
J 2
(8000 3900);
DISPLAY 0.617021 (8000 3900);
PAINT SKYBLUE (8000 3900);
FORCEPROP 1 LAST PART_NUMBER G22178-002
J 0
(7775 4100);
DISPLAY 0.617021 (7775 4100);
PAINT BLUE (7775 4100);
FORCEPROP 1 LAST PACK_TYPE 0603
J 0
(8100 4000);
DISPLAY 0.617021 (8100 4000);
PAINT SKYBLUE (8100 4000);
FORCEPROP 1 LAST TOLERANCE 5.0%
J 0
(8025 3950);
DISPLAY 0.617021 (8025 3950);
PAINT SKYBLUE (8025 3950);
FORCEPROP 1 LAST MATERIAL CHIP
J 0
(8025 3900);
DISPLAY 0.617021 (8025 3900);
PAINT SKYBLUE (8025 3900);
FORCEPROP 2 LAST CDS_LIB mstr_discrete
J 0
(8025 4050);
PAINT MONO (8025 4050);
DISPLAY INVISIBLE (8025 4050);
FORCEPROP 1 LAST PATH I153
J 0
(7975 4200);
DISPLAY 0.978723 (7975 4200);
PAINT WHITE (7975 4200);
DISPLAY INVISIBLE (7975 4200);
FORCEPROP 0 LAST BOM_COST NT_GBE_BASE
J 0
(8125 4275);
DISPLAY 1.021277 (8125 4275);
PAINT ORANGE (8125 4275);
DISPLAY INVISIBLE (8125 4275);
FORCEPROP 0 LAST ROOM NIC_SPRV
J 0
(8125 4175);
DISPLAY 1.021277 (8125 4175);
PAINT ORANGE (8125 4175);
DISPLAY INVISIBLE (8125 4175);
FORCEPROP 0 LAST SEC 1
J 0
(7775 4150);
DISPLAY 0.680851 (7775 4150);
PAINT MONO (7775 4150);
DISPLAY INVISIBLE (7775 4150);
FORCEPROP 2 LAST SEC_TYPE 0603
J 0
(7975 4250);
DISPLAY 1.021277 (7975 4250);
PAINT ORANGE (7975 4250);
DISPLAY INVISIBLE (7975 4250);
FORCEADD RES..1
(8050 2325);
FORCEPROP 1 LAST LOCATION RT46
J 0
(8150 2350);
DISPLAY 0.617021 (8150 2350);
PAINT AQUA (8150 2350);
FORCEPROP 1 LAST VALUE 0
J 2
(8000 2275);
DISPLAY 0.617021 (8000 2275);
PAINT SKYBLUE (8000 2275);
FORCEPROP 1 LAST PACK_TYPE 0603
J 0
(8125 2275);
DISPLAY 0.617021 (8125 2275);
PAINT SKYBLUE (8125 2275);
FORCEPROP 1 LASTPIN (7950 2325) $PN 1
J 0
(7962 2337);
DISPLAY 0.787234 (7962 2337);
PAINT ORANGE (7962 2337);
FORCEPROP 1 LASTPIN (8150 2325) $PN 2
J 0
(8112 2337);
DISPLAY 0.787234 (8112 2337);
PAINT ORANGE (8112 2337);
FORCEPROP 1 LAST WATTAGE 1/10W
J 2
(8025 2175);
DISPLAY 0.617021 (8025 2175);
PAINT SKYBLUE (8025 2175);
FORCEPROP 1 LAST MATERIAL CHIP
J 0
(8050 2175);
DISPLAY 0.617021 (8050 2175);
PAINT SKYBLUE (8050 2175);
FORCEPROP 1 LAST TOLERANCE 5.0%
J 0
(8050 2225);
DISPLAY 0.617021 (8050 2225);
PAINT SKYBLUE (8050 2225);
FORCEPROP 1 LAST PART_NUMBER G22178-002
J 0
(7800 2375);
DISPLAY 0.617021 (7800 2375);
PAINT BLUE (7800 2375);
FORCEPROP 0 LAST BOM_COST NT_GBE_BASE
J 0
(8150 2550);
DISPLAY 1.021277 (8150 2550);
PAINT ORANGE (8150 2550);
DISPLAY INVISIBLE (8150 2550);
FORCEPROP 0 LAST ROOM NIC_SPRV
J 0
(8150 2450);
DISPLAY 1.021277 (8150 2450);
PAINT ORANGE (8150 2450);
DISPLAY INVISIBLE (8150 2450);
FORCEPROP 1 LAST PATH I154
J 0
(8000 2475);
DISPLAY 0.978723 (8000 2475);
PAINT WHITE (8000 2475);
DISPLAY INVISIBLE (8000 2475);
FORCEPROP 2 LAST CDS_LIB mstr_discrete
J 0
(8050 2325);
PAINT MONO (8050 2325);
DISPLAY INVISIBLE (8050 2325);
FORCEPROP 0 LAST SEC 1
J 0
(7800 2425);
DISPLAY 0.680851 (7800 2425);
PAINT MONO (7800 2425);
DISPLAY INVISIBLE (7800 2425);
FORCEPROP 2 LAST SEC_TYPE 0603
J 0
(8000 2525);
DISPLAY 1.021277 (8000 2525);
PAINT ORANGE (8000 2525);
DISPLAY INVISIBLE (8000 2525);
FORCEADD SC22U16V5MX-4-GP..1
(11150 975);
FORCEPROP 1 LAST LOCATION C22W23
J 0
(11250 1110);
DISPLAY 0.617021 (11250 1110);
PAINT GREEN (11250 1110);
FORCEPROP 1 LAST VALUE SC22U16V5MX-4-GP
R 1
J 0
(11225 745);
DISPLAY 0.617021 (11225 745);
PAINT GREEN (11225 745);
FORCEPROP 2 LASTPIN (11150 1050) $PN 1
R 1
J 0
(11140 1060);
DISPLAY 0.808511 (11140 1060);
PAINT ORANGE (11140 1060);
FORCEPROP 2 LAST ATTRIBUTE 22UF
J 0
(11250 1050);
DISPLAY 0.638298 (11250 1050);
PAINT GREEN (11250 1050);
FORCEPROP 2 LAST TOLERANCE 20%
J 0
(11250 1000);
DISPLAY 0.638298 (11250 1000);
PAINT GREEN (11250 1000);
FORCEPROP 2 LASTPIN (11150 900) $PN 2
R 1
J 2
(11140 890);
DISPLAY 0.808511 (11140 890);
PAINT ORANGE (11140 890);
FORCEPROP 2 LAST PACK_SIZE 0805
J 0
(11250 850);
DISPLAY 0.638298 (11250 850);
PAINT GREEN (11250 850);
FORCEPROP 2 LAST TYPE X6S
J 0
(11250 900);
DISPLAY 0.638298 (11250 900);
PAINT GREEN (11250 900);
FORCEPROP 2 LAST RATED 16V
J 0
(11250 950);
DISPLAY 0.638298 (11250 950);
PAINT GREEN (11250 950);
FORCEPROP 1 LAST PATH I159
J 0
(11150 975);
DISPLAY 0.617021 (11150 975);
PAINT GREEN (11150 975);
DISPLAY INVISIBLE (11150 975);
FORCEPROP 1 LAST CDS_LMAN_SYM_OUTLINE -50,25,50,-25
J 0
(11150 975);
DISPLAY 0.468085 (11150 975);
PAINT GREEN (11150 975);
DISPLAY INVISIBLE (11150 975);
FORCEPROP 2 LAST CDS_LIB w_hdl
J 0
(11150 975);
PAINT MONO (11150 975);
DISPLAY INVISIBLE (11150 975);
FORCEPROP 1 LAST PART_NUMBER 078.22611.0811
J 0
(11150 975);
DISPLAY 0.617021 (11150 975);
PAINT GREEN (11150 975);
DISPLAY INVISIBLE (11150 975);
FORCEPROP 2 LAST SEC_TYPE SMD-BCG5
J 0
(11175 1050);
DISPLAY 1.021277 (11175 1050);
PAINT ORANGE (11175 1050);
DISPLAY INVISIBLE (11175 1050);
FORCEPROP 2 LAST SEC 1
J 0
(11175 1050);
DISPLAY 0.680851 (11175 1050);
PAINT MONO (11175 1050);
DISPLAY INVISIBLE (11175 1050);
FORCEPROP 1 LAST PACK_TYPE SMD-BCG5
J 0
(11150 975);
DISPLAY 0.617021 (11150 975);
PAINT GREEN (11150 975);
DISPLAY INVISIBLE (11150 975);
FORCEADD CAP..1
(8125 4575);
FORCEPROP 1 LAST PART_NUMBER A36096-155
J 0
(8325 4625);
DISPLAY 0.617021 (8325 4625);
PAINT BLUE (8325 4625);
FORCEPROP 1 LAST PACK_TYPE 0402
J 0
(8325 4575);
DISPLAY 0.617021 (8325 4575);
PAINT SKYBLUE (8325 4575);
FORCEPROP 1 LAST TOLERANCE 10%
J 0
(8175 4525);
DISPLAY 0.617021 (8175 4525);
PAINT SKYBLUE (8175 4525);
FORCEPROP 1 LAST MATERIAL X7R
J 0
(8325 4675);
DISPLAY 0.617021 (8325 4675);
PAINT SKYBLUE (8325 4675);
FORCEPROP 1 LAST VALUE 0.22UF
J 0
(8175 4625);
DISPLAY 0.617021 (8175 4625);
PAINT SKYBLUE (8175 4625);
FORCEPROP 1 LAST VOLTAGE 16V
J 0
(8175 4575);
DISPLAY 0.617021 (8175 4575);
PAINT SKYBLUE (8175 4575);
FORCEPROP 1 LASTPIN (8125 4675) $PN 1
J 0
(8135 4655);
DISPLAY 0.617021 (8135 4655);
PAINT WHITE (8135 4655);
FORCEPROP 1 LAST LOCATION C7A8
J 0
(8175 4675);
DISPLAY 0.617021 (8175 4675);
PAINT AQUA (8175 4675);
FORCEPROP 1 LASTPIN (8125 4475) $PN 2
J 0
(8135 4455);
DISPLAY 0.617021 (8135 4455);
PAINT WHITE (8135 4455);
FORCEPROP 2 LAST CDS_LIB mstr_discrete
J 0
(8125 4575);
DISPLAY 1.617021 (8125 4575);
PAINT ORANGE (8125 4575);
DISPLAY INVISIBLE (8125 4575);
FORCEPROP 2 LAST SEC_TYPE 0402
J 0
(8175 4775);
DISPLAY 1.659574 (8175 4775);
PAINT ORANGE (8175 4775);
DISPLAY INVISIBLE (8175 4775);
FORCEPROP 2 LAST SEC 1
J 0
(8175 4775);
DISPLAY 1.106383 (8175 4775);
PAINT MONO (8175 4775);
DISPLAY INVISIBLE (8175 4775);
FORCEPROP 2 LAST CDS_LOCATION C7A8
J 0
(8175 4675);
DISPLAY 0.617021 (8175 4675);
PAINT AQUA (8175 4675);
DISPLAY INVISIBLE (8175 4675);
FORCEPROP 1 LAST PATH I16
J 0
(8175 4725);
DISPLAY 0.978723 (8175 4725);
PAINT WHITE (8175 4725);
DISPLAY INVISIBLE (8175 4725);
FORCEPROP 2 LAST ROOM PVNN_PCH_STBY
J 0
(8175 4725);
DISPLAY 2.212766 (8175 4725);
PAINT WHITE (8175 4725);
DISPLAY INVISIBLE (8175 4725);
FORCEADD SC22U16V5MX-4-GP..1
(11450 975);
FORCEPROP 1 LAST LOCATION C22W24
J 0
(11550 1110);
DISPLAY 0.617021 (11550 1110);
PAINT GREEN (11550 1110);
FORCEPROP 1 LAST VALUE SC22U16V5MX-4-GP
R 1
J 0
(11525 745);
DISPLAY 0.617021 (11525 745);
PAINT GREEN (11525 745);
FORCEPROP 2 LASTPIN (11450 1050) $PN 1
R 1
J 0
(11440 1060);
DISPLAY 0.808511 (11440 1060);
PAINT ORANGE (11440 1060);
FORCEPROP 2 LAST ATTRIBUTE 22UF
J 0
(11550 1050);
DISPLAY 0.638298 (11550 1050);
PAINT GREEN (11550 1050);
FORCEPROP 2 LAST TOLERANCE 20%
J 0
(11550 1000);
DISPLAY 0.638298 (11550 1000);
PAINT GREEN (11550 1000);
FORCEPROP 2 LASTPIN (11450 900) $PN 2
R 1
J 2
(11440 890);
DISPLAY 0.808511 (11440 890);
PAINT ORANGE (11440 890);
FORCEPROP 2 LAST PACK_SIZE 0805
J 0
(11550 850);
DISPLAY 0.638298 (11550 850);
PAINT GREEN (11550 850);
FORCEPROP 2 LAST TYPE X6S
J 0
(11550 900);
DISPLAY 0.638298 (11550 900);
PAINT GREEN (11550 900);
FORCEPROP 2 LAST RATED 16V
J 0
(11550 950);
DISPLAY 0.638298 (11550 950);
PAINT GREEN (11550 950);
FORCEPROP 1 LAST PATH I160
J 0
(11450 975);
DISPLAY 0.617021 (11450 975);
PAINT GREEN (11450 975);
DISPLAY INVISIBLE (11450 975);
FORCEPROP 1 LAST CDS_LMAN_SYM_OUTLINE -50,25,50,-25
J 0
(11450 975);
DISPLAY 0.468085 (11450 975);
PAINT GREEN (11450 975);
DISPLAY INVISIBLE (11450 975);
FORCEPROP 2 LAST CDS_LIB w_hdl
J 0
(11450 975);
PAINT MONO (11450 975);
DISPLAY INVISIBLE (11450 975);
FORCEPROP 1 LAST PART_NUMBER 078.22611.0811
J 0
(11450 975);
DISPLAY 0.617021 (11450 975);
PAINT GREEN (11450 975);
DISPLAY INVISIBLE (11450 975);
FORCEPROP 2 LAST SEC_TYPE SMD-BCG5
J 0
(11475 1050);
DISPLAY 1.021277 (11475 1050);
PAINT ORANGE (11475 1050);
DISPLAY INVISIBLE (11475 1050);
FORCEPROP 2 LAST SEC 1
J 0
(11475 1050);
DISPLAY 0.680851 (11475 1050);
PAINT MONO (11475 1050);
DISPLAY INVISIBLE (11475 1050);
FORCEPROP 1 LAST PACK_TYPE SMD-BCG5
J 0
(11450 975);
DISPLAY 0.617021 (11450 975);
PAINT GREEN (11450 975);
DISPLAY INVISIBLE (11450 975);
FORCEADD SC22U16V5MX-4-GP..1
(11800 975);
FORCEPROP 1 LAST LOCATION C7A13
J 0
(11900 1110);
DISPLAY 0.617021 (11900 1110);
PAINT GREEN (11900 1110);
FORCEPROP 1 LAST VALUE SC22U16V5MX-4-GP
R 1
J 0
(11875 745);
DISPLAY 0.617021 (11875 745);
PAINT GREEN (11875 745);
FORCEPROP 2 LASTPIN (11800 900) $PN 2
R 1
J 2
(11790 890);
DISPLAY 0.808511 (11790 890);
PAINT ORANGE (11790 890);
FORCEPROP 2 LASTPIN (11800 1050) $PN 1
R 1
J 0
(11790 1060);
DISPLAY 0.808511 (11790 1060);
PAINT ORANGE (11790 1060);
FORCEPROP 2 LAST PACK_SIZE 0805
J 0
(11900 850);
DISPLAY 0.638298 (11900 850);
PAINT GREEN (11900 850);
FORCEPROP 2 LAST TYPE X6S
J 0
(11900 900);
DISPLAY 0.638298 (11900 900);
PAINT GREEN (11900 900);
FORCEPROP 2 LAST RATED 16V
J 0
(11900 950);
DISPLAY 0.638298 (11900 950);
PAINT GREEN (11900 950);
FORCEPROP 2 LAST TOLERANCE 20%
J 0
(11900 1000);
DISPLAY 0.638298 (11900 1000);
PAINT GREEN (11900 1000);
FORCEPROP 2 LAST ATTRIBUTE 22UF
J 0
(11900 1050);
DISPLAY 0.638298 (11900 1050);
PAINT GREEN (11900 1050);
FORCEPROP 1 LAST PATH I161
J 0
(11800 975);
DISPLAY 0.617021 (11800 975);
PAINT GREEN (11800 975);
DISPLAY INVISIBLE (11800 975);
FORCEPROP 1 LAST PACK_TYPE SMD-BCG5
J 0
(11800 975);
DISPLAY 0.617021 (11800 975);
PAINT GREEN (11800 975);
DISPLAY INVISIBLE (11800 975);
FORCEPROP 2 LAST SEC 1
J 0
(11825 1050);
DISPLAY 0.680851 (11825 1050);
PAINT MONO (11825 1050);
DISPLAY INVISIBLE (11825 1050);
FORCEPROP 2 LAST SEC_TYPE SMD-BCG5
J 0
(11825 1050);
DISPLAY 1.021277 (11825 1050);
PAINT ORANGE (11825 1050);
DISPLAY INVISIBLE (11825 1050);
FORCEPROP 1 LAST PART_NUMBER 078.22611.0811
J 0
(11800 975);
DISPLAY 0.617021 (11800 975);
PAINT GREEN (11800 975);
DISPLAY INVISIBLE (11800 975);
FORCEPROP 2 LAST CDS_LIB w_hdl
J 0
(11800 975);
PAINT MONO (11800 975);
DISPLAY INVISIBLE (11800 975);
FORCEPROP 1 LAST CDS_LMAN_SYM_OUTLINE -50,25,50,-25
J 0
(11800 975);
DISPLAY 0.468085 (11800 975);
PAINT GREEN (11800 975);
DISPLAY INVISIBLE (11800 975);
FORCEADD SC22U16V5MX-4-GP..1
(12100 975);
FORCEPROP 1 LAST LOCATION C22W25
J 0
(12200 1110);
DISPLAY 0.617021 (12200 1110);
PAINT GREEN (12200 1110);
FORCEPROP 2 LAST ATTRIBUTE 22UF
J 0
(12200 1050);
DISPLAY 0.638298 (12200 1050);
PAINT GREEN (12200 1050);
FORCEPROP 1 LAST VALUE SC22U16V5MX-4-GP
R 1
J 0
(12175 745);
DISPLAY 0.617021 (12175 745);
PAINT GREEN (12175 745);
FORCEPROP 2 LAST TOLERANCE 20%
J 0
(12200 1000);
DISPLAY 0.638298 (12200 1000);
PAINT GREEN (12200 1000);
FORCEPROP 2 LAST TYPE X6S
J 0
(12200 900);
DISPLAY 0.638298 (12200 900);
PAINT GREEN (12200 900);
FORCEPROP 2 LAST PACK_SIZE 0805
J 0
(12200 850);
DISPLAY 0.638298 (12200 850);
PAINT GREEN (12200 850);
FORCEPROP 2 LAST RATED 16V
J 0
(12200 950);
DISPLAY 0.638298 (12200 950);
PAINT GREEN (12200 950);
FORCEPROP 2 LASTPIN (12100 1050) $PN 1
R 1
J 0
(12090 1060);
DISPLAY 0.808511 (12090 1060);
PAINT ORANGE (12090 1060);
FORCEPROP 2 LASTPIN (12100 900) $PN 2
R 1
J 2
(12090 890);
DISPLAY 0.808511 (12090 890);
PAINT ORANGE (12090 890);
FORCEPROP 1 LAST PATH I162
J 0
(12100 975);
DISPLAY 0.617021 (12100 975);
PAINT GREEN (12100 975);
DISPLAY INVISIBLE (12100 975);
FORCEPROP 1 LAST CDS_LMAN_SYM_OUTLINE -50,25,50,-25
J 0
(12100 975);
DISPLAY 0.468085 (12100 975);
PAINT GREEN (12100 975);
DISPLAY INVISIBLE (12100 975);
FORCEPROP 2 LAST CDS_LIB w_hdl
J 0
(12100 975);
PAINT MONO (12100 975);
DISPLAY INVISIBLE (12100 975);
FORCEPROP 1 LAST PART_NUMBER 078.22611.0811
J 0
(12100 975);
DISPLAY 0.617021 (12100 975);
PAINT GREEN (12100 975);
DISPLAY INVISIBLE (12100 975);
FORCEPROP 2 LAST SEC_TYPE SMD-BCG5
J 0
(12125 1050);
DISPLAY 1.021277 (12125 1050);
PAINT ORANGE (12125 1050);
DISPLAY INVISIBLE (12125 1050);
FORCEPROP 2 LAST SEC 1
J 0
(12125 1050);
DISPLAY 0.680851 (12125 1050);
PAINT MONO (12125 1050);
DISPLAY INVISIBLE (12125 1050);
FORCEPROP 1 LAST PACK_TYPE SMD-BCG5
J 0
(12100 975);
DISPLAY 0.617021 (12100 975);
PAINT GREEN (12100 975);
DISPLAY INVISIBLE (12100 975);
FORCEADD SC22U16V5MX-4-GP..1
(12700 975);
FORCEPROP 1 LAST VALUE SC22U16V5MX-4-GP
R 1
J 0
(12775 745);
DISPLAY 0.617021 (12775 745);
PAINT GREEN (12775 745);
FORCEPROP 2 LASTPIN (12700 1050) $PN 1
R 1
J 0
(12690 1060);
DISPLAY 0.808511 (12690 1060);
PAINT ORANGE (12690 1060);
FORCEPROP 2 LAST ATTRIBUTE 22UF
J 0
(12800 1050);
DISPLAY 0.638298 (12800 1050);
PAINT GREEN (12800 1050);
FORCEPROP 1 LAST LOCATION C22W27
J 0
(12800 1110);
DISPLAY 0.617021 (12800 1110);
PAINT GREEN (12800 1110);
FORCEPROP 2 LAST RATED 16V
J 0
(12800 950);
DISPLAY 0.638298 (12800 950);
PAINT GREEN (12800 950);
FORCEPROP 2 LAST TYPE X6S
J 0
(12800 900);
DISPLAY 0.638298 (12800 900);
PAINT GREEN (12800 900);
FORCEPROP 2 LASTPIN (12700 900) $PN 2
R 1
J 2
(12690 890);
DISPLAY 0.808511 (12690 890);
PAINT ORANGE (12690 890);
FORCEPROP 2 LAST TOLERANCE 20%
J 0
(12800 1000);
DISPLAY 0.638298 (12800 1000);
PAINT GREEN (12800 1000);
FORCEPROP 2 LAST PACK_SIZE 0805
J 0
(12800 850);
DISPLAY 0.638298 (12800 850);
PAINT GREEN (12800 850);
FORCEPROP 1 LAST PACK_TYPE SMD-BCG5
J 0
(12700 975);
DISPLAY 0.617021 (12700 975);
PAINT GREEN (12700 975);
DISPLAY INVISIBLE (12700 975);
FORCEPROP 2 LAST SEC 1
J 0
(12725 1050);
DISPLAY 0.680851 (12725 1050);
PAINT MONO (12725 1050);
DISPLAY INVISIBLE (12725 1050);
FORCEPROP 2 LAST SEC_TYPE SMD-BCG5
J 0
(12725 1050);
DISPLAY 1.021277 (12725 1050);
PAINT ORANGE (12725 1050);
DISPLAY INVISIBLE (12725 1050);
FORCEPROP 1 LAST PART_NUMBER 078.22611.0811
J 0
(12700 975);
DISPLAY 0.617021 (12700 975);
PAINT GREEN (12700 975);
DISPLAY INVISIBLE (12700 975);
FORCEPROP 2 LAST CDS_LIB w_hdl
J 0
(12700 975);
PAINT MONO (12700 975);
DISPLAY INVISIBLE (12700 975);
FORCEPROP 1 LAST CDS_LMAN_SYM_OUTLINE -50,25,50,-25
J 0
(12700 975);
DISPLAY 0.468085 (12700 975);
PAINT GREEN (12700 975);
DISPLAY INVISIBLE (12700 975);
FORCEPROP 1 LAST PATH I163
J 0
(12700 975);
DISPLAY 0.617021 (12700 975);
PAINT GREEN (12700 975);
DISPLAY INVISIBLE (12700 975);
FORCEADD GND..1
(12700 725);
FORCEPROP 3 LASTPIN (12700 775) SIG_NAME GND\g
J 0
(12710 785);
DISPLAY 0.659574 (12710 785);
PAINT MONO (12710 785);
DISPLAY INVISIBLE (12710 785);
FORCEPROP 2 LAST CDS_LIB mstr_symbols
J 0
(12700 725);
PAINT MONO (12700 725);
DISPLAY INVISIBLE (12700 725);
FORCEPROP 2 LAST BOM_COST PVPP_KLM_VR
J 0
(11850 800);
DISPLAY 1.042553 (11850 800);
PAINT WHITE (11850 800);
DISPLAY INVISIBLE (11850 800);
FORCEPROP 2 LAST ROOM PVPP_KLM_VR
J 0
(12125 800);
DISPLAY 1.042553 (12125 800);
PAINT GREEN (12125 800);
DISPLAY INVISIBLE (12125 800);
FORCEPROP 1 LAST BODY_TYPE PLUMBING
J 0
(12655 682);
DISPLAY 0.340426 (12655 682);
PAINT GREEN (12655 682);
DISPLAY INVISIBLE (12655 682);
FORCEPROP 1 LAST VOLTAGE 0
J 0
(12700 725);
PAINT SKYBLUE (12700 725);
DISPLAY INVISIBLE (12700 725);
FORCEPROP 1 LAST SIZE 1B
J 0
(12775 675);
DISPLAY 0.872340 (12775 675);
PAINT GREEN (12775 675);
DISPLAY INVISIBLE (12775 675);
FORCEPROP 1 LAST HDL_POWER GND
J 0
(12700 875);
DISPLAY 0.872340 (12700 875);
PAINT GREEN (12700 875);
DISPLAY INVISIBLE (12700 875);
FORCEPROP 1 LAST PATH I164
J 0
(12775 725);
DISPLAY 0.872340 (12775 725);
PAINT AQUA (12775 725);
DISPLAY INVISIBLE (12775 725);
FORCEADD SC22U16V5MX-4-GP..1
(12400 975);
FORCEPROP 2 LAST ATTRIBUTE 22UF
J 0
(12500 1050);
DISPLAY 0.638298 (12500 1050);
PAINT GREEN (12500 1050);
FORCEPROP 2 LAST TYPE X6S
J 0
(12500 900);
DISPLAY 0.638298 (12500 900);
PAINT GREEN (12500 900);
FORCEPROP 2 LAST PACK_SIZE 0805
J 0
(12500 850);
DISPLAY 0.638298 (12500 850);
PAINT GREEN (12500 850);
FORCEPROP 2 LAST RATED 16V
J 0
(12500 950);
DISPLAY 0.638298 (12500 950);
PAINT GREEN (12500 950);
FORCEPROP 2 LAST TOLERANCE 20%
J 0
(12500 1000);
DISPLAY 0.638298 (12500 1000);
PAINT GREEN (12500 1000);
FORCEPROP 1 LAST LOCATION C22W26
J 0
(12500 1110);
DISPLAY 0.617021 (12500 1110);
PAINT GREEN (12500 1110);
FORCEPROP 1 LAST VALUE SC22U16V5MX-4-GP
R 1
J 0
(12475 745);
DISPLAY 0.617021 (12475 745);
PAINT GREEN (12475 745);
FORCEPROP 2 LASTPIN (12400 1050) $PN 1
R 1
J 0
(12390 1060);
DISPLAY 0.808511 (12390 1060);
PAINT ORANGE (12390 1060);
FORCEPROP 2 LASTPIN (12400 900) $PN 2
R 1
J 2
(12390 890);
DISPLAY 0.808511 (12390 890);
PAINT ORANGE (12390 890);
FORCEPROP 1 LAST PATH I165
J 0
(12400 975);
DISPLAY 0.617021 (12400 975);
PAINT GREEN (12400 975);
DISPLAY INVISIBLE (12400 975);
FORCEPROP 1 LAST CDS_LMAN_SYM_OUTLINE -50,25,50,-25
J 0
(12400 975);
DISPLAY 0.468085 (12400 975);
PAINT GREEN (12400 975);
DISPLAY INVISIBLE (12400 975);
FORCEPROP 2 LAST CDS_LIB w_hdl
J 0
(12400 975);
PAINT MONO (12400 975);
DISPLAY INVISIBLE (12400 975);
FORCEPROP 1 LAST PART_NUMBER 078.22611.0811
J 0
(12400 975);
DISPLAY 0.617021 (12400 975);
PAINT GREEN (12400 975);
DISPLAY INVISIBLE (12400 975);
FORCEPROP 2 LAST SEC_TYPE SMD-BCG5
J 0
(12425 1050);
DISPLAY 1.021277 (12425 1050);
PAINT ORANGE (12425 1050);
DISPLAY INVISIBLE (12425 1050);
FORCEPROP 2 LAST SEC 1
J 0
(12425 1050);
DISPLAY 0.680851 (12425 1050);
PAINT MONO (12425 1050);
DISPLAY INVISIBLE (12425 1050);
FORCEPROP 1 LAST PACK_TYPE SMD-BCG5
J 0
(12400 975);
DISPLAY 0.617021 (12400 975);
PAINT GREEN (12400 975);
DISPLAY INVISIBLE (12400 975);
FORCEADD GND..1
(12400 725);
FORCEPROP 3 LASTPIN (12400 775) SIG_NAME GND\g
J 0
(12410 785);
DISPLAY 0.659574 (12410 785);
PAINT MONO (12410 785);
DISPLAY INVISIBLE (12410 785);
FORCEPROP 1 LAST PATH I166
J 0
(12475 725);
DISPLAY 0.872340 (12475 725);
PAINT AQUA (12475 725);
DISPLAY INVISIBLE (12475 725);
FORCEPROP 2 LAST CDS_LIB mstr_symbols
J 0
(12400 725);
PAINT MONO (12400 725);
DISPLAY INVISIBLE (12400 725);
FORCEPROP 2 LAST BOM_COST PVPP_KLM_VR
J 0
(11550 800);
DISPLAY 1.042553 (11550 800);
PAINT WHITE (11550 800);
DISPLAY INVISIBLE (11550 800);
FORCEPROP 2 LAST ROOM PVPP_KLM_VR
J 0
(11825 800);
DISPLAY 1.042553 (11825 800);
PAINT GREEN (11825 800);
DISPLAY INVISIBLE (11825 800);
FORCEPROP 1 LAST BODY_TYPE PLUMBING
J 0
(12355 682);
DISPLAY 0.340426 (12355 682);
PAINT GREEN (12355 682);
DISPLAY INVISIBLE (12355 682);
FORCEPROP 1 LAST VOLTAGE 0
J 0
(12400 725);
PAINT SKYBLUE (12400 725);
DISPLAY INVISIBLE (12400 725);
FORCEPROP 1 LAST SIZE 1B
J 0
(12475 675);
DISPLAY 0.872340 (12475 675);
PAINT GREEN (12475 675);
DISPLAY INVISIBLE (12475 675);
FORCEPROP 1 LAST HDL_POWER GND
J 0
(12400 875);
DISPLAY 0.872340 (12400 875);
PAINT GREEN (12400 875);
DISPLAY INVISIBLE (12400 875);
FORCEADD GND..1
(12100 725);
FORCEPROP 3 LASTPIN (12100 775) SIG_NAME GND\g
J 0
(12110 785);
DISPLAY 0.659574 (12110 785);
PAINT MONO (12110 785);
DISPLAY INVISIBLE (12110 785);
FORCEPROP 1 LAST PATH I167
J 0
(12175 725);
DISPLAY 0.872340 (12175 725);
PAINT AQUA (12175 725);
DISPLAY INVISIBLE (12175 725);
FORCEPROP 2 LAST CDS_LIB mstr_symbols
J 0
(12100 725);
PAINT MONO (12100 725);
DISPLAY INVISIBLE (12100 725);
FORCEPROP 2 LAST BOM_COST PVPP_KLM_VR
J 0
(11250 800);
DISPLAY 1.042553 (11250 800);
PAINT WHITE (11250 800);
DISPLAY INVISIBLE (11250 800);
FORCEPROP 2 LAST ROOM PVPP_KLM_VR
J 0
(11525 800);
DISPLAY 1.042553 (11525 800);
PAINT GREEN (11525 800);
DISPLAY INVISIBLE (11525 800);
FORCEPROP 1 LAST BODY_TYPE PLUMBING
J 0
(12055 682);
DISPLAY 0.340426 (12055 682);
PAINT GREEN (12055 682);
DISPLAY INVISIBLE (12055 682);
FORCEPROP 1 LAST VOLTAGE 0
J 0
(12100 725);
PAINT SKYBLUE (12100 725);
DISPLAY INVISIBLE (12100 725);
FORCEPROP 1 LAST SIZE 1B
J 0
(12175 675);
DISPLAY 0.872340 (12175 675);
PAINT GREEN (12175 675);
DISPLAY INVISIBLE (12175 675);
FORCEPROP 1 LAST HDL_POWER GND
J 0
(12100 875);
DISPLAY 0.872340 (12100 875);
PAINT GREEN (12100 875);
DISPLAY INVISIBLE (12100 875);
FORCEADD GND..1
(11800 725);
FORCEPROP 3 LASTPIN (11800 775) SIG_NAME GND\g
J 0
(11810 785);
DISPLAY 0.659574 (11810 785);
PAINT MONO (11810 785);
DISPLAY INVISIBLE (11810 785);
FORCEPROP 1 LAST PATH I168
J 0
(11875 725);
DISPLAY 0.872340 (11875 725);
PAINT AQUA (11875 725);
DISPLAY INVISIBLE (11875 725);
FORCEPROP 2 LAST CDS_LIB mstr_symbols
J 0
(11800 725);
PAINT MONO (11800 725);
DISPLAY INVISIBLE (11800 725);
FORCEPROP 2 LAST BOM_COST PVPP_KLM_VR
J 0
(10950 800);
DISPLAY 1.042553 (10950 800);
PAINT WHITE (10950 800);
DISPLAY INVISIBLE (10950 800);
FORCEPROP 2 LAST ROOM PVPP_KLM_VR
J 0
(11225 800);
DISPLAY 1.042553 (11225 800);
PAINT GREEN (11225 800);
DISPLAY INVISIBLE (11225 800);
FORCEPROP 1 LAST BODY_TYPE PLUMBING
J 0
(11755 682);
DISPLAY 0.340426 (11755 682);
PAINT GREEN (11755 682);
DISPLAY INVISIBLE (11755 682);
FORCEPROP 1 LAST VOLTAGE 0
J 0
(11800 725);
PAINT SKYBLUE (11800 725);
DISPLAY INVISIBLE (11800 725);
FORCEPROP 1 LAST SIZE 1B
J 0
(11875 675);
DISPLAY 0.872340 (11875 675);
PAINT GREEN (11875 675);
DISPLAY INVISIBLE (11875 675);
FORCEPROP 1 LAST HDL_POWER GND
J 0
(11800 875);
DISPLAY 0.872340 (11800 875);
PAINT GREEN (11800 875);
DISPLAY INVISIBLE (11800 875);
FORCEADD GND..1
(11450 725);
FORCEPROP 3 LASTPIN (11450 775) SIG_NAME GND\g
J 0
(11460 785);
DISPLAY 0.659574 (11460 785);
PAINT MONO (11460 785);
DISPLAY INVISIBLE (11460 785);
FORCEPROP 1 LAST PATH I169
J 0
(11525 725);
DISPLAY 0.872340 (11525 725);
PAINT AQUA (11525 725);
DISPLAY INVISIBLE (11525 725);
FORCEPROP 1 LAST HDL_POWER GND
J 0
(11450 875);
DISPLAY 0.872340 (11450 875);
PAINT GREEN (11450 875);
DISPLAY INVISIBLE (11450 875);
FORCEPROP 1 LAST SIZE 1B
J 0
(11525 675);
DISPLAY 0.872340 (11525 675);
PAINT GREEN (11525 675);
DISPLAY INVISIBLE (11525 675);
FORCEPROP 1 LAST VOLTAGE 0
J 0
(11450 725);
PAINT SKYBLUE (11450 725);
DISPLAY INVISIBLE (11450 725);
FORCEPROP 1 LAST BODY_TYPE PLUMBING
J 0
(11405 682);
DISPLAY 0.340426 (11405 682);
PAINT GREEN (11405 682);
DISPLAY INVISIBLE (11405 682);
FORCEPROP 2 LAST ROOM PVPP_KLM_VR
J 0
(10875 800);
DISPLAY 1.042553 (10875 800);
PAINT GREEN (10875 800);
DISPLAY INVISIBLE (10875 800);
FORCEPROP 2 LAST BOM_COST PVPP_KLM_VR
J 0
(10600 800);
DISPLAY 1.042553 (10600 800);
PAINT WHITE (10600 800);
DISPLAY INVISIBLE (10600 800);
FORCEPROP 2 LAST CDS_LIB mstr_symbols
J 0
(11450 725);
PAINT MONO (11450 725);
DISPLAY INVISIBLE (11450 725);
FORCEADD GND..1
(11150 725);
FORCEPROP 3 LASTPIN (11150 775) SIG_NAME GND\g
J 0
(11160 785);
DISPLAY 0.659574 (11160 785);
PAINT MONO (11160 785);
DISPLAY INVISIBLE (11160 785);
FORCEPROP 1 LAST PATH I170
J 0
(11225 725);
DISPLAY 0.872340 (11225 725);
PAINT AQUA (11225 725);
DISPLAY INVISIBLE (11225 725);
FORCEPROP 2 LAST CDS_LIB mstr_symbols
J 0
(11150 725);
PAINT MONO (11150 725);
DISPLAY INVISIBLE (11150 725);
FORCEPROP 2 LAST BOM_COST PVPP_KLM_VR
J 0
(10300 800);
DISPLAY 1.042553 (10300 800);
PAINT WHITE (10300 800);
DISPLAY INVISIBLE (10300 800);
FORCEPROP 2 LAST ROOM PVPP_KLM_VR
J 0
(10575 800);
DISPLAY 1.042553 (10575 800);
PAINT GREEN (10575 800);
DISPLAY INVISIBLE (10575 800);
FORCEPROP 1 LAST BODY_TYPE PLUMBING
J 0
(11105 682);
DISPLAY 0.340426 (11105 682);
PAINT GREEN (11105 682);
DISPLAY INVISIBLE (11105 682);
FORCEPROP 1 LAST VOLTAGE 0
J 0
(11150 725);
PAINT SKYBLUE (11150 725);
DISPLAY INVISIBLE (11150 725);
FORCEPROP 1 LAST SIZE 1B
J 0
(11225 675);
DISPLAY 0.872340 (11225 675);
PAINT GREEN (11225 675);
DISPLAY INVISIBLE (11225 675);
FORCEPROP 1 LAST HDL_POWER GND
J 0
(11150 875);
DISPLAY 0.872340 (11150 875);
PAINT GREEN (11150 875);
DISPLAY INVISIBLE (11150 875);
FORCEADD SC22U16V5MX-4-GP..1
(10850 975);
FORCEPROP 1 LAST VALUE SC22U16V5MX-4-GP
R 1
J 0
(10925 745);
DISPLAY 0.617021 (10925 745);
PAINT GREEN (10925 745);
FORCEPROP 2 LASTPIN (10850 1050) $PN 1
R 1
J 0
(10840 1060);
DISPLAY 0.808511 (10840 1060);
PAINT ORANGE (10840 1060);
FORCEPROP 1 LAST LOCATION C22W22
J 0
(10950 1110);
DISPLAY 0.617021 (10950 1110);
PAINT GREEN (10950 1110);
FORCEPROP 2 LAST ATTRIBUTE 22UF
J 0
(10950 1050);
DISPLAY 0.638298 (10950 1050);
PAINT GREEN (10950 1050);
FORCEPROP 2 LAST TOLERANCE 20%
J 0
(10950 1000);
DISPLAY 0.638298 (10950 1000);
PAINT GREEN (10950 1000);
FORCEPROP 2 LASTPIN (10850 900) $PN 2
R 1
J 2
(10840 890);
DISPLAY 0.808511 (10840 890);
PAINT ORANGE (10840 890);
FORCEPROP 2 LAST RATED 16V
J 0
(10950 950);
DISPLAY 0.638298 (10950 950);
PAINT GREEN (10950 950);
FORCEPROP 2 LAST TYPE X6S
J 0
(10950 900);
DISPLAY 0.638298 (10950 900);
PAINT GREEN (10950 900);
FORCEPROP 2 LAST PACK_SIZE 0805
J 0
(10950 850);
DISPLAY 0.638298 (10950 850);
PAINT GREEN (10950 850);
FORCEPROP 1 LAST PATH I171
J 0
(10850 975);
DISPLAY 0.617021 (10850 975);
PAINT GREEN (10850 975);
DISPLAY INVISIBLE (10850 975);
FORCEPROP 1 LAST CDS_LMAN_SYM_OUTLINE -50,25,50,-25
J 0
(10850 975);
DISPLAY 0.468085 (10850 975);
PAINT GREEN (10850 975);
DISPLAY INVISIBLE (10850 975);
FORCEPROP 2 LAST CDS_LIB w_hdl
J 0
(10850 975);
PAINT MONO (10850 975);
DISPLAY INVISIBLE (10850 975);
FORCEPROP 1 LAST PART_NUMBER 078.22611.0811
J 0
(10850 975);
DISPLAY 0.617021 (10850 975);
PAINT GREEN (10850 975);
DISPLAY INVISIBLE (10850 975);
FORCEPROP 2 LAST SEC_TYPE SMD-BCG5
J 0
(10875 1050);
DISPLAY 1.021277 (10875 1050);
PAINT ORANGE (10875 1050);
DISPLAY INVISIBLE (10875 1050);
FORCEPROP 2 LAST SEC 1
J 0
(10875 1050);
DISPLAY 0.680851 (10875 1050);
PAINT MONO (10875 1050);
DISPLAY INVISIBLE (10875 1050);
FORCEPROP 1 LAST PACK_TYPE SMD-BCG5
J 0
(10850 975);
DISPLAY 0.617021 (10850 975);
PAINT GREEN (10850 975);
DISPLAY INVISIBLE (10850 975);
FORCEADD SC22U16V5MX-4-GP..1
(10550 975);
FORCEPROP 2 LASTPIN (10550 1050) $PN 1
R 1
J 0
(10540 1060);
DISPLAY 0.808511 (10540 1060);
PAINT ORANGE (10540 1060);
FORCEPROP 1 LAST LOCATION C7A14
J 0
(10650 1110);
DISPLAY 0.617021 (10650 1110);
PAINT GREEN (10650 1110);
FORCEPROP 2 LAST ATTRIBUTE 22UF
J 0
(10650 1050);
DISPLAY 0.638298 (10650 1050);
PAINT GREEN (10650 1050);
FORCEPROP 2 LAST TOLERANCE 20%
J 0
(10650 1000);
DISPLAY 0.638298 (10650 1000);
PAINT GREEN (10650 1000);
FORCEPROP 2 LASTPIN (10550 900) $PN 2
R 1
J 2
(10540 890);
DISPLAY 0.808511 (10540 890);
PAINT ORANGE (10540 890);
FORCEPROP 1 LAST VALUE SC22U16V5MX-4-GP
R 1
J 0
(10625 745);
DISPLAY 0.617021 (10625 745);
PAINT GREEN (10625 745);
FORCEPROP 2 LAST RATED 16V
J 0
(10650 950);
DISPLAY 0.638298 (10650 950);
PAINT GREEN (10650 950);
FORCEPROP 2 LAST TYPE X6S
J 0
(10650 900);
DISPLAY 0.638298 (10650 900);
PAINT GREEN (10650 900);
FORCEPROP 2 LAST PACK_SIZE 0805
J 0
(10650 850);
DISPLAY 0.638298 (10650 850);
PAINT GREEN (10650 850);
FORCEPROP 1 LAST PATH I172
J 0
(10550 975);
DISPLAY 0.617021 (10550 975);
PAINT GREEN (10550 975);
DISPLAY INVISIBLE (10550 975);
FORCEPROP 1 LAST CDS_LMAN_SYM_OUTLINE -50,25,50,-25
J 0
(10550 975);
DISPLAY 0.468085 (10550 975);
PAINT GREEN (10550 975);
DISPLAY INVISIBLE (10550 975);
FORCEPROP 2 LAST CDS_LIB w_hdl
J 0
(10550 975);
PAINT MONO (10550 975);
DISPLAY INVISIBLE (10550 975);
FORCEPROP 1 LAST PART_NUMBER 078.22611.0811
J 0
(10550 975);
DISPLAY 0.617021 (10550 975);
PAINT GREEN (10550 975);
DISPLAY INVISIBLE (10550 975);
FORCEPROP 2 LAST SEC_TYPE SMD-BCG5
J 0
(10575 1050);
DISPLAY 1.021277 (10575 1050);
PAINT ORANGE (10575 1050);
DISPLAY INVISIBLE (10575 1050);
FORCEPROP 2 LAST SEC 1
J 0
(10575 1050);
DISPLAY 0.680851 (10575 1050);
PAINT MONO (10575 1050);
DISPLAY INVISIBLE (10575 1050);
FORCEPROP 1 LAST PACK_TYPE SMD-BCG5
J 0
(10550 975);
DISPLAY 0.617021 (10550 975);
PAINT GREEN (10550 975);
DISPLAY INVISIBLE (10550 975);
FORCEADD GND..1
(10850 725);
FORCEPROP 3 LASTPIN (10850 775) SIG_NAME GND\g
J 0
(10860 785);
DISPLAY 0.659574 (10860 785);
PAINT MONO (10860 785);
DISPLAY INVISIBLE (10860 785);
FORCEPROP 1 LAST PATH I173
J 0
(10925 725);
DISPLAY 0.872340 (10925 725);
PAINT AQUA (10925 725);
DISPLAY INVISIBLE (10925 725);
FORCEPROP 2 LAST CDS_LIB mstr_symbols
J 0
(10850 725);
PAINT MONO (10850 725);
DISPLAY INVISIBLE (10850 725);
FORCEPROP 2 LAST BOM_COST PVPP_KLM_VR
J 0
(10000 800);
DISPLAY 1.042553 (10000 800);
PAINT WHITE (10000 800);
DISPLAY INVISIBLE (10000 800);
FORCEPROP 2 LAST ROOM PVPP_KLM_VR
J 0
(10275 800);
DISPLAY 1.042553 (10275 800);
PAINT GREEN (10275 800);
DISPLAY INVISIBLE (10275 800);
FORCEPROP 1 LAST BODY_TYPE PLUMBING
J 0
(10805 682);
DISPLAY 0.340426 (10805 682);
PAINT GREEN (10805 682);
DISPLAY INVISIBLE (10805 682);
FORCEPROP 1 LAST VOLTAGE 0
J 0
(10850 725);
PAINT SKYBLUE (10850 725);
DISPLAY INVISIBLE (10850 725);
FORCEPROP 1 LAST SIZE 1B
J 0
(10925 675);
DISPLAY 0.872340 (10925 675);
PAINT GREEN (10925 675);
DISPLAY INVISIBLE (10925 675);
FORCEPROP 1 LAST HDL_POWER GND
J 0
(10850 875);
DISPLAY 0.872340 (10850 875);
PAINT GREEN (10850 875);
DISPLAY INVISIBLE (10850 875);
FORCEADD GND..1
(10550 725);
FORCEPROP 3 LASTPIN (10550 775) SIG_NAME GND\g
J 0
(10560 785);
DISPLAY 0.659574 (10560 785);
PAINT MONO (10560 785);
DISPLAY INVISIBLE (10560 785);
FORCEPROP 1 LAST PATH I174
J 0
(10625 725);
DISPLAY 0.872340 (10625 725);
PAINT AQUA (10625 725);
DISPLAY INVISIBLE (10625 725);
FORCEPROP 2 LAST CDS_LIB mstr_symbols
J 0
(10550 725);
PAINT MONO (10550 725);
DISPLAY INVISIBLE (10550 725);
FORCEPROP 2 LAST BOM_COST PVPP_KLM_VR
J 0
(9700 800);
DISPLAY 1.042553 (9700 800);
PAINT WHITE (9700 800);
DISPLAY INVISIBLE (9700 800);
FORCEPROP 2 LAST ROOM PVPP_KLM_VR
J 0
(9975 800);
DISPLAY 1.042553 (9975 800);
PAINT GREEN (9975 800);
DISPLAY INVISIBLE (9975 800);
FORCEPROP 1 LAST BODY_TYPE PLUMBING
J 0
(10505 682);
DISPLAY 0.340426 (10505 682);
PAINT GREEN (10505 682);
DISPLAY INVISIBLE (10505 682);
FORCEPROP 1 LAST VOLTAGE 0
J 0
(10550 725);
PAINT SKYBLUE (10550 725);
DISPLAY INVISIBLE (10550 725);
FORCEPROP 1 LAST SIZE 1B
J 0
(10625 675);
DISPLAY 0.872340 (10625 675);
PAINT GREEN (10625 675);
DISPLAY INVISIBLE (10625 675);
FORCEPROP 1 LAST HDL_POWER GND
J 0
(10550 875);
DISPLAY 0.872340 (10550 875);
PAINT GREEN (10550 875);
DISPLAY INVISIBLE (10550 875);
FORCEADD RES..1
(7425 5050);
FORCEPROP 1 LAST MATERIAL CHIP
J 0
(7650 4950);
DISPLAY 0.510638 (7650 4950);
PAINT SKYBLUE (7650 4950);
FORCEPROP 1 LAST PACK_TYPE 0402
J 0
(7500 4950);
DISPLAY 0.617021 (7500 4950);
PAINT SKYBLUE (7500 4950);
FORCEPROP 1 LAST PART_NUMBER G21497-005
J 0
(7300 5000);
DISPLAY 0.617021 (7300 5000);
PAINT BLUE (7300 5000);
FORCEPROP 1 LAST WATTAGE 1/16W
J 2
(7775 5075);
DISPLAY 0.510638 (7775 5075);
PAINT SKYBLUE (7775 5075);
FORCEPROP 1 LASTPIN (7325 5050) $PN 1
J 0
(7337 5062);
DISPLAY 0.617021 (7337 5062);
PAINT WHITE (7337 5062);
FORCEPROP 1 LAST VALUE 0.0
J 2
(7325 4950);
DISPLAY 0.617021 (7325 4950);
PAINT SKYBLUE (7325 4950);
FORCEPROP 1 LASTPIN (7525 5050) $PN 2
J 0
(7487 5062);
DISPLAY 0.617021 (7487 5062);
PAINT WHITE (7487 5062);
FORCEPROP 1 LAST LOCATION R3L1
J 0
(7325 5100);
DISPLAY 0.617021 (7325 5100);
PAINT AQUA (7325 5100);
FORCEPROP 1 LAST TOLERANCE 5%
J 0
(7375 4950);
DISPLAY 0.617021 (7375 4950);
PAINT SKYBLUE (7375 4950);
FORCEPROP 2 LAST CDS_LOCATION R3L1
J 0
(6950 5050);
DISPLAY 0.617021 (6950 5050);
PAINT AQUA (6950 5050);
DISPLAY INVISIBLE (6950 5050);
FORCEPROP 0 LAST CDS_SEC 1
J 0
(7725 5100);
PAINT MONO (7725 5100);
DISPLAY INVISIBLE (7725 5100);
FORCEPROP 2 LAST ROOM CPU0
J 0
(7375 5200);
PAINT PEACH (7375 5200);
DISPLAY INVISIBLE (7375 5200);
FORCEPROP 2 LAST SEC 1
J 0
(7375 5275);
DISPLAY 0.680851 (7375 5275);
PAINT MONO (7375 5275);
DISPLAY INVISIBLE (7375 5275);
FORCEPROP 2 LAST SEC_TYPE 0402
J 0
(7375 5275);
DISPLAY 1.021277 (7375 5275);
PAINT ORANGE (7375 5275);
DISPLAY INVISIBLE (7375 5275);
FORCEPROP 2 LAST CDS_LIB mstr_discrete
J 0
(7425 5050);
DISPLAY 1.340426 (7425 5050);
PAINT ORANGE (7425 5050);
DISPLAY INVISIBLE (7425 5050);
FORCEPROP 2 LAST BOM_COST PROC_SIDEBAND
J 0
(7425 5050);
PAINT MONO (7425 5050);
DISPLAY INVISIBLE (7425 5050);
FORCEPROP 1 LAST PATH I175
J 0
(7375 5200);
DISPLAY 0.978723 (7375 5200);
PAINT WHITE (7375 5200);
DISPLAY INVISIBLE (7375 5200);
FORCEADD RES..1
(7325 3300);
FORCEPROP 1 LAST WATTAGE 1/16W
J 2
(7675 3350);
DISPLAY 0.510638 (7675 3350);
PAINT SKYBLUE (7675 3350);
FORCEPROP 1 LAST MATERIAL CHIP
J 0
(7525 3200);
DISPLAY 0.510638 (7525 3200);
PAINT SKYBLUE (7525 3200);
FORCEPROP 1 LAST LOCATION R3L4
J 0
(7225 3350);
DISPLAY 0.617021 (7225 3350);
PAINT AQUA (7225 3350);
FORCEPROP 1 LAST VALUE 0.0
J 2
(7225 3200);
DISPLAY 0.617021 (7225 3200);
PAINT SKYBLUE (7225 3200);
FORCEPROP 1 LASTPIN (7425 3300) $PN 2
J 0
(7387 3312);
DISPLAY 0.617021 (7387 3312);
PAINT WHITE (7387 3312);
FORCEPROP 1 LASTPIN (7225 3300) $PN 1
J 0
(7237 3312);
DISPLAY 0.617021 (7237 3312);
PAINT WHITE (7237 3312);
FORCEPROP 1 LAST PART_NUMBER G21497-005
J 0
(7200 3250);
DISPLAY 0.617021 (7200 3250);
PAINT BLUE (7200 3250);
FORCEPROP 1 LAST TOLERANCE 5%
J 0
(7275 3200);
DISPLAY 0.617021 (7275 3200);
PAINT SKYBLUE (7275 3200);
FORCEPROP 1 LAST PACK_TYPE 0402
J 0
(7400 3200);
DISPLAY 0.617021 (7400 3200);
PAINT SKYBLUE (7400 3200);
FORCEPROP 2 LAST CDS_LOCATION R3L4
J 0
(6850 3300);
DISPLAY 0.617021 (6850 3300);
PAINT AQUA (6850 3300);
DISPLAY INVISIBLE (6850 3300);
FORCEPROP 1 LAST PATH I177
J 0
(7275 3450);
DISPLAY 0.978723 (7275 3450);
PAINT WHITE (7275 3450);
DISPLAY INVISIBLE (7275 3450);
FORCEPROP 0 LAST CDS_SEC 1
J 0
(7625 3350);
PAINT MONO (7625 3350);
DISPLAY INVISIBLE (7625 3350);
FORCEPROP 2 LAST ROOM CPU0
J 0
(7275 3450);
PAINT PEACH (7275 3450);
DISPLAY INVISIBLE (7275 3450);
FORCEPROP 2 LAST SEC 1
J 0
(7275 3525);
DISPLAY 0.680851 (7275 3525);
PAINT MONO (7275 3525);
DISPLAY INVISIBLE (7275 3525);
FORCEPROP 2 LAST SEC_TYPE 0402
J 0
(7275 3525);
DISPLAY 1.021277 (7275 3525);
PAINT ORANGE (7275 3525);
DISPLAY INVISIBLE (7275 3525);
FORCEPROP 2 LAST CDS_LIB mstr_discrete
J 0
(7325 3300);
DISPLAY 1.340426 (7325 3300);
PAINT ORANGE (7325 3300);
DISPLAY INVISIBLE (7325 3300);
FORCEPROP 2 LAST BOM_COST PROC_SIDEBAND
J 0
(7325 3300);
PAINT MONO (7325 3300);
DISPLAY INVISIBLE (7325 3300);
FORCEADD IND-300NH-20-GP..1
R 1
(11375 4000);
FORCEPROP 2 LASTPIN (11525 3975) $PN 2
J 0
(11535 3985);
DISPLAY 0.808511 (11535 3985);
PAINT ORANGE (11535 3985);
FORCEPROP 1 LAST VALUE IND-300NH-20-GP
J 0
(11200 3925);
DISPLAY 0.617021 (11200 3925);
PAINT GREEN (11200 3925);
FORCEPROP 2 LASTPIN (11225 3975) $PN 1
J 2
(11215 3985);
DISPLAY 0.808511 (11215 3985);
PAINT ORANGE (11215 3985);
FORCEPROP 1 LAST LOCATION L7A2
J 0
(11225 4050);
DISPLAY 0.617021 (11225 4050);
PAINT GREEN (11225 4050);
FORCEPROP 2 LAST ATTRIBUTE 300NH
J 0
(11200 3875);
DISPLAY 0.638298 (11200 3875);
PAINT GREEN (11200 3875);
FORCEPROP 2 LAST RATED ISAT=33A@25C
J 0
(11200 3825);
DISPLAY 0.638298 (11200 3825);
PAINT GREEN (11200 3825);
FORCEPROP 2 LAST PACK_SIZE DCR=0.17MOHM
J 0
(11200 3725);
DISPLAY 0.638298 (11200 3725);
PAINT GREEN (11200 3725);
FORCEPROP 2 LAST TYPE IRMS=66A@DELTA_T<40C
J 0
(11200 3775);
DISPLAY 0.638298 (11200 3775);
PAINT GREEN (11200 3775);
FORCEPROP 1 LAST PATH I178
R 1
J 0
(11375 4000);
DISPLAY 0.617021 (11375 4000);
PAINT GREEN (11375 4000);
DISPLAY INVISIBLE (11375 4000);
FORCEPROP 1 LAST PACK_TYPE DISCRET-GB1
R 1
J 0
(11375 4000);
DISPLAY 0.617021 (11375 4000);
PAINT GREEN (11375 4000);
DISPLAY INVISIBLE (11375 4000);
FORCEPROP 2 LAST SEC 1
J 0
(11225 4100);
DISPLAY 0.680851 (11225 4100);
PAINT MONO (11225 4100);
DISPLAY INVISIBLE (11225 4100);
FORCEPROP 2 LAST SEC_TYPE DISCRET-GB1
J 0
(11225 4100);
DISPLAY 1.021277 (11225 4100);
PAINT ORANGE (11225 4100);
DISPLAY INVISIBLE (11225 4100);
FORCEPROP 1 LAST CDS_LMAN_SYM_OUTLINE -75,100,75,-100
R 1
J 0
(11375 4000);
DISPLAY 0.468085 (11375 4000);
PAINT GREEN (11375 4000);
DISPLAY INVISIBLE (11375 4000);
FORCEPROP 2 LAST CDS_LIB w_hdl
R 1
J 0
(11375 4000);
PAINT MONO (11375 4000);
DISPLAY INVISIBLE (11375 4000);
FORCEPROP 1 LAST PART_NUMBER 068.3012N.M001
R 1
J 0
(11375 4000);
DISPLAY 0.617021 (11375 4000);
PAINT GREEN (11375 4000);
DISPLAY INVISIBLE (11375 4000);
FORCEADD IND-300NH-20-GP..1
R 1
(11400 2300);
FORCEPROP 2 LASTPIN (11250 2275) $PN 1
J 2
(11240 2285);
DISPLAY 0.808511 (11240 2285);
PAINT ORANGE (11240 2285);
FORCEPROP 2 LASTPIN (11550 2275) $PN 2
J 0
(11560 2285);
DISPLAY 0.808511 (11560 2285);
PAINT ORANGE (11560 2285);
FORCEPROP 1 LAST LOCATION L7A4
J 0
(11250 2400);
DISPLAY 0.617021 (11250 2400);
PAINT GREEN (11250 2400);
FORCEPROP 1 LAST VALUE IND-300NH-20-GP
J 0
(11225 2225);
DISPLAY 0.617021 (11225 2225);
PAINT GREEN (11225 2225);
FORCEPROP 2 LAST ATTRIBUTE 300NH
J 0
(11400 2400);
DISPLAY 0.638298 (11400 2400);
PAINT GREEN (11400 2400);
FORCEPROP 2 LAST RATED ISAT=33A@25C
J 0
(11400 2350);
DISPLAY 0.638298 (11400 2350);
PAINT GREEN (11400 2350);
FORCEPROP 2 LAST PACK_SIZE DCR=0.17MOHM
J 0
(11700 2350);
DISPLAY 0.638298 (11700 2350);
PAINT GREEN (11700 2350);
FORCEPROP 2 LAST TYPE IRMS=66A@DELTA_T<40C
J 0
(11700 2400);
DISPLAY 0.638298 (11700 2400);
PAINT GREEN (11700 2400);
FORCEPROP 1 LAST PACK_TYPE DISCRET-GB1
R 1
J 0
(11400 2300);
DISPLAY 0.617021 (11400 2300);
PAINT GREEN (11400 2300);
DISPLAY INVISIBLE (11400 2300);
FORCEPROP 2 LAST SEC 1
J 0
(11250 2400);
DISPLAY 0.680851 (11250 2400);
PAINT MONO (11250 2400);
DISPLAY INVISIBLE (11250 2400);
FORCEPROP 2 LAST SEC_TYPE DISCRET-GB1
J 0
(11250 2400);
DISPLAY 1.021277 (11250 2400);
PAINT ORANGE (11250 2400);
DISPLAY INVISIBLE (11250 2400);
FORCEPROP 1 LAST CDS_LMAN_SYM_OUTLINE -75,100,75,-100
R 1
J 0
(11400 2300);
DISPLAY 0.468085 (11400 2300);
PAINT GREEN (11400 2300);
DISPLAY INVISIBLE (11400 2300);
FORCEPROP 2 LAST CDS_LIB w_hdl
R 1
J 0
(11400 2300);
PAINT MONO (11400 2300);
DISPLAY INVISIBLE (11400 2300);
FORCEPROP 1 LAST PART_NUMBER 068.3012N.M001
R 1
J 0
(11400 2300);
DISPLAY 0.617021 (11400 2300);
PAINT GREEN (11400 2300);
DISPLAY INVISIBLE (11400 2300);
FORCEPROP 1 LAST PATH I179
R 1
J 0
(11400 2300);
DISPLAY 0.617021 (11400 2300);
PAINT GREEN (11400 2300);
DISPLAY INVISIBLE (11400 2300);
FORCEADD SC1U10V2KX-4-GP..1
(7800 4525);
FORCEPROP 2 LAST PACK_SIZE 0402
J 0
(7925 4400);
DISPLAY 0.638298 (7925 4400);
PAINT GREEN (7925 4400);
FORCEPROP 2 LAST RATED 10V
J 0
(7925 4450);
DISPLAY 0.638298 (7925 4450);
PAINT GREEN (7925 4450);
FORCEPROP 2 LAST TOLERANCE 10%
J 0
(7925 4500);
DISPLAY 0.638298 (7925 4500);
PAINT GREEN (7925 4500);
FORCEPROP 2 LAST ATTRIBUTE 1UF
J 0
(7925 4550);
DISPLAY 0.638298 (7925 4550);
PAINT GREEN (7925 4550);
FORCEPROP 1 LAST VALUE SC1U10V2KX-4-GP
R 1
J 0
(7900 4300);
DISPLAY 0.617021 (7900 4300);
PAINT GREEN (7900 4300);
FORCEPROP 2 LASTPIN (7800 4600) $PN 1
R 1
J 0
(7790 4610);
DISPLAY 0.808511 (7790 4610);
PAINT ORANGE (7790 4610);
FORCEPROP 1 LAST LOCATION C3L1
J 0
(7925 4605);
DISPLAY 0.617021 (7925 4605);
PAINT GREEN (7925 4605);
FORCEPROP 2 LASTPIN (7800 4450) $PN 2
R 1
J 2
(7790 4440);
DISPLAY 0.808511 (7790 4440);
PAINT ORANGE (7790 4440);
FORCEPROP 1 LAST CDS_LMAN_SYM_OUTLINE -50,25,50,-25
J 0
(7800 4525);
DISPLAY 0.468085 (7800 4525);
PAINT GREEN (7800 4525);
DISPLAY INVISIBLE (7800 4525);
FORCEPROP 1 LAST PATH I180
J 0
(7800 4525);
DISPLAY 0.617021 (7800 4525);
PAINT GREEN (7800 4525);
DISPLAY INVISIBLE (7800 4525);
FORCEPROP 2 LAST CDS_LIB w_hdl
J 0
(7800 4525);
PAINT MONO (7800 4525);
DISPLAY INVISIBLE (7800 4525);
FORCEPROP 1 LAST PART_NUMBER 78.10523.8FL
J 0
(7800 4525);
DISPLAY 0.617021 (7800 4525);
PAINT GREEN (7800 4525);
DISPLAY INVISIBLE (7800 4525);
FORCEPROP 2 LAST SEC_TYPE SMD-BCG6
J 0
(7825 4600);
DISPLAY 1.021277 (7825 4600);
PAINT ORANGE (7825 4600);
DISPLAY INVISIBLE (7825 4600);
FORCEPROP 2 LAST SEC 1
J 0
(7825 4600);
DISPLAY 0.680851 (7825 4600);
PAINT MONO (7825 4600);
DISPLAY INVISIBLE (7825 4600);
FORCEPROP 1 LAST PACK_TYPE SMD-BCG6
J 0
(7800 4525);
DISPLAY 0.617021 (7800 4525);
PAINT GREEN (7800 4525);
DISPLAY INVISIBLE (7800 4525);
FORCEADD SC1U10V2KX-4-GP..1
(7625 2775);
FORCEPROP 2 LASTPIN (7625 2850) $PN 1
R 1
J 0
(7615 2860);
DISPLAY 0.808511 (7615 2860);
PAINT ORANGE (7615 2860);
FORCEPROP 2 LASTPIN (7625 2700) $PN 2
R 1
J 2
(7615 2690);
DISPLAY 0.808511 (7615 2690);
PAINT ORANGE (7615 2690);
FORCEPROP 1 LAST VALUE SC1U10V2KX-4-GP
R 1
J 0
(7725 2575);
DISPLAY 0.617021 (7725 2575);
PAINT GREEN (7725 2575);
FORCEPROP 1 LAST LOCATION C3L29
J 0
(7750 2855);
DISPLAY 0.617021 (7750 2855);
PAINT GREEN (7750 2855);
FORCEPROP 2 LAST ATTRIBUTE 1UF
J 0
(7750 2800);
DISPLAY 0.638298 (7750 2800);
PAINT GREEN (7750 2800);
FORCEPROP 2 LAST TOLERANCE 10%
J 0
(7750 2750);
DISPLAY 0.638298 (7750 2750);
PAINT GREEN (7750 2750);
FORCEPROP 2 LAST RATED 10V
J 0
(7750 2700);
DISPLAY 0.638298 (7750 2700);
PAINT GREEN (7750 2700);
FORCEPROP 2 LAST PACK_SIZE 0402
J 0
(7750 2650);
DISPLAY 0.638298 (7750 2650);
PAINT GREEN (7750 2650);
FORCEPROP 1 LAST CDS_LMAN_SYM_OUTLINE -50,25,50,-25
J 0
(7625 2775);
DISPLAY 0.468085 (7625 2775);
PAINT GREEN (7625 2775);
DISPLAY INVISIBLE (7625 2775);
FORCEPROP 1 LAST PATH I181
J 0
(7625 2775);
DISPLAY 0.617021 (7625 2775);
PAINT GREEN (7625 2775);
DISPLAY INVISIBLE (7625 2775);
FORCEPROP 2 LAST CDS_LIB w_hdl
J 0
(7625 2775);
PAINT MONO (7625 2775);
DISPLAY INVISIBLE (7625 2775);
FORCEPROP 1 LAST PART_NUMBER 78.10523.8FL
J 0
(7625 2775);
DISPLAY 0.617021 (7625 2775);
PAINT GREEN (7625 2775);
DISPLAY INVISIBLE (7625 2775);
FORCEPROP 2 LAST SEC_TYPE SMD-BCG6
J 0
(7625 2825);
DISPLAY 1.021277 (7625 2825);
PAINT ORANGE (7625 2825);
DISPLAY INVISIBLE (7625 2825);
FORCEPROP 2 LAST SEC 1
J 0
(7625 2825);
DISPLAY 0.680851 (7625 2825);
PAINT MONO (7625 2825);
DISPLAY INVISIBLE (7625 2825);
FORCEPROP 1 LAST PACK_TYPE SMD-BCG6
J 0
(7625 2775);
DISPLAY 0.617021 (7625 2775);
PAINT GREEN (7625 2775);
DISPLAY INVISIBLE (7625 2775);
FORCEADD 1R3F-GP..1
(10550 3550);
FORCEPROP 2 LAST PACK_SIZE 0603
J 0
(10600 3425);
DISPLAY 0.638298 (10600 3425);
PAINT GREEN (10600 3425);
FORCEPROP 2 LAST RATED 1/10W
J 0
(10600 3475);
DISPLAY 0.638298 (10600 3475);
PAINT GREEN (10600 3475);
FORCEPROP 1 LAST LOCATION RT43
J 0
(10600 3675);
DISPLAY 0.617021 (10600 3675);
PAINT GREEN (10600 3675);
FORCEPROP 1 LAST VALUE 1R3F-GP
J 0
(10600 3625);
DISPLAY 0.617021 (10600 3625);
PAINT GREEN (10600 3625);
FORCEPROP 2 LAST ATTRIBUTE 1 OHM
J 0
(10600 3575);
DISPLAY 0.638298 (10600 3575);
PAINT GREEN (10600 3575);
FORCEPROP 2 LAST TOLERANCE 1%
J 0
(10600 3525);
DISPLAY 0.638298 (10600 3525);
PAINT GREEN (10600 3525);
FORCEPROP 0 LAST POP NOPOP
J 0
(10600 3375);
DISPLAY 0.638298 (10600 3375);
PAINT RED (10600 3375);
FORCEPROP 2 LASTPIN (10550 3675) $PN 1
R 1
J 0
(10540 3685);
DISPLAY 0.808511 (10540 3685);
PAINT ORANGE (10540 3685);
FORCEPROP 2 LASTPIN (10550 3425) $PN 2
R 1
J 2
(10540 3415);
DISPLAY 0.808511 (10540 3415);
PAINT ORANGE (10540 3415);
FORCEPROP 1 LAST CDS_LMAN_SYM_OUTLINE -50,75,50,-75
J 0
(10550 3550);
DISPLAY 0.468085 (10550 3550);
PAINT GREEN (10550 3550);
DISPLAY INVISIBLE (10550 3550);
FORCEPROP 2 LAST CDS_LIB w_hdl
J 0
(10550 3550);
DISPLAY INVISIBLE (10550 3550);
FORCEPROP 1 LAST PART_NUMBER 64.1R005.55L
J 0
(10550 3550);
DISPLAY 0.617021 (10550 3550);
PAINT GREEN (10550 3550);
DISPLAY INVISIBLE (10550 3550);
FORCEPROP 2 LAST SEC_TYPE RCL_GP
J 0
(10600 3650);
DISPLAY 1.021277 (10600 3650);
PAINT ORANGE (10600 3650);
DISPLAY INVISIBLE (10600 3650);
FORCEPROP 2 LAST SEC 1
J 0
(10600 3650);
DISPLAY 0.680851 (10600 3650);
PAINT MONO (10600 3650);
DISPLAY INVISIBLE (10600 3650);
FORCEPROP 1 LAST PACK_TYPE RCL_GP
J 0
(10550 3550);
DISPLAY 0.617021 (10550 3550);
PAINT GREEN (10550 3550);
DISPLAY INVISIBLE (10550 3550);
FORCEPROP 1 LAST PATH I182
J 0
(10550 3550);
DISPLAY 0.617021 (10550 3550);
PAINT GREEN (10550 3550);
DISPLAY INVISIBLE (10550 3550);
FORCEADD 1R3F-GP..1
(11050 1850);
FORCEPROP 2 LAST PACK_SIZE 0603
J 0
(11100 1725);
DISPLAY 0.638298 (11100 1725);
PAINT GREEN (11100 1725);
FORCEPROP 1 LAST LOCATION RT45
J 0
(11100 1975);
DISPLAY 0.617021 (11100 1975);
PAINT GREEN (11100 1975);
FORCEPROP 2 LAST RATED 1/10W
J 0
(11100 1775);
DISPLAY 0.638298 (11100 1775);
PAINT GREEN (11100 1775);
FORCEPROP 2 LAST ATTRIBUTE 1 OHM
J 0
(11100 1875);
DISPLAY 0.638298 (11100 1875);
PAINT GREEN (11100 1875);
FORCEPROP 2 LAST TOLERANCE 1%
J 0
(11100 1825);
DISPLAY 0.638298 (11100 1825);
PAINT GREEN (11100 1825);
FORCEPROP 2 LASTPIN (11050 1725) $PN 2
R 1
J 2
(11040 1715);
DISPLAY 0.808511 (11040 1715);
PAINT ORANGE (11040 1715);
FORCEPROP 2 LASTPIN (11050 1975) $PN 1
R 1
J 0
(11040 1985);
DISPLAY 0.808511 (11040 1985);
PAINT ORANGE (11040 1985);
FORCEPROP 0 LAST POP NOPOP
J 0
(11100 1675);
DISPLAY 0.638298 (11100 1675);
PAINT RED (11100 1675);
FORCEPROP 1 LAST VALUE 1R3F-GP
J 0
(11100 1925);
DISPLAY 0.617021 (11100 1925);
PAINT GREEN (11100 1925);
FORCEPROP 1 LAST PACK_TYPE RCL_GP
J 0
(11050 1850);
DISPLAY 0.617021 (11050 1850);
PAINT GREEN (11050 1850);
DISPLAY INVISIBLE (11050 1850);
FORCEPROP 2 LAST SEC 1
J 0
(11100 1950);
DISPLAY 0.680851 (11100 1950);
PAINT MONO (11100 1950);
DISPLAY INVISIBLE (11100 1950);
FORCEPROP 2 LAST SEC_TYPE RCL_GP
J 0
(11100 1950);
DISPLAY 1.021277 (11100 1950);
PAINT ORANGE (11100 1950);
DISPLAY INVISIBLE (11100 1950);
FORCEPROP 1 LAST PART_NUMBER 64.1R005.55L
J 0
(11050 1850);
DISPLAY 0.617021 (11050 1850);
PAINT GREEN (11050 1850);
DISPLAY INVISIBLE (11050 1850);
FORCEPROP 2 LAST CDS_LIB w_hdl
J 0
(11050 1850);
DISPLAY INVISIBLE (11050 1850);
FORCEPROP 1 LAST CDS_LMAN_SYM_OUTLINE -50,75,50,-75
J 0
(11050 1850);
DISPLAY 0.468085 (11050 1850);
PAINT GREEN (11050 1850);
DISPLAY INVISIBLE (11050 1850);
FORCEPROP 1 LAST PATH I183
J 0
(11050 1850);
DISPLAY 0.617021 (11050 1850);
PAINT GREEN (11050 1850);
DISPLAY INVISIBLE (11050 1850);
FORCEADD CAP..1
(7300 4500);
FORCEPROP 1 LASTPIN (7300 4400) $PN 2
J 0
(7310 4380);
DISPLAY 0.617021 (7310 4380);
PAINT WHITE (7310 4380);
FORCEPROP 1 LAST MATERIAL X6S
J 0
(7350 4400);
DISPLAY 0.617021 (7350 4400);
PAINT SKYBLUE (7350 4400);
FORCEPROP 1 LAST TOLERANCE 10%
J 0
(7350 4450);
DISPLAY 0.617021 (7350 4450);
PAINT SKYBLUE (7350 4450);
FORCEPROP 1 LAST VOLTAGE 16V
J 0
(7350 4500);
DISPLAY 0.617021 (7350 4500);
PAINT SKYBLUE (7350 4500);
FORCEPROP 1 LAST PART_NUMBER D97712-011
J 0
(7350 4350);
DISPLAY 0.617021 (7350 4350);
PAINT BLUE (7350 4350);
FORCEPROP 1 LAST LOCATION C7A6
J 0
(7350 4600);
DISPLAY 0.617021 (7350 4600);
PAINT AQUA (7350 4600);
FORCEPROP 1 LAST PACK_TYPE 0402
J 0
(7350 4300);
DISPLAY 0.617021 (7350 4300);
PAINT SKYBLUE (7350 4300);
FORCEPROP 1 LAST VALUE 1.0UF
J 0
(7350 4550);
DISPLAY 0.617021 (7350 4550);
PAINT SKYBLUE (7350 4550);
FORCEPROP 1 LASTPIN (7300 4600) $PN 1
J 0
(7310 4580);
DISPLAY 0.617021 (7310 4580);
PAINT WHITE (7310 4580);
FORCEPROP 2 LAST CDS_LIB mstr_discrete
J 0
(7300 4500);
DISPLAY 1.617021 (7300 4500);
PAINT ORANGE (7300 4500);
DISPLAY INVISIBLE (7300 4500);
FORCEPROP 2 LAST CDS_LOCATION C7A6
J 0
(7350 4600);
DISPLAY 0.617021 (7350 4600);
PAINT AQUA (7350 4600);
DISPLAY INVISIBLE (7350 4600);
FORCEPROP 2 LAST SEC_TYPE 0402
J 0
(7350 4700);
DISPLAY 1.659574 (7350 4700);
PAINT ORANGE (7350 4700);
DISPLAY INVISIBLE (7350 4700);
FORCEPROP 2 LAST SEC 1
J 0
(7350 4700);
DISPLAY 1.106383 (7350 4700);
PAINT MONO (7350 4700);
DISPLAY INVISIBLE (7350 4700);
FORCEPROP 1 LAST PATH I19
J 0
(7350 4650);
DISPLAY 0.978723 (7350 4650);
PAINT WHITE (7350 4650);
DISPLAY INVISIBLE (7350 4650);
FORCEPROP 2 LAST ROOM P1V05_PCH_STBY_VR
J 0
(7350 4650);
DISPLAY 2.212766 (7350 4650);
PAINT WHITE (7350 4650);
DISPLAY INVISIBLE (7350 4650);
FORCEADD OFFPAGE..2
(11325 4825);
FORCEPROP 2 LAST $XR0 235 
J 0
(11514 4825);
DISPLAY 0.638298 (11514 4825);
PAINT MONO (11514 4825);
FORCEPROP 2 LAST ROOM PVCCIO_CPU0
J 0
(10925 4900);
DISPLAY 3.127660 (10925 4900);
PAINT WHITE (10925 4900);
DISPLAY INVISIBLE (10925 4900);
FORCEPROP 2 LAST BOM_COST PROC_VRD_PVCCIO_CPU0
J 0
(11525 4875);
DISPLAY 2.340426 (11525 4875);
PAINT WHITE (11525 4875);
DISPLAY INVISIBLE (11525 4875);
FORCEPROP 2 LAST CDS_LIB mstr_standard
J 0
(11325 4825);
DISPLAY 1.617021 (11325 4825);
PAINT ORANGE (11325 4825);
DISPLAY INVISIBLE (11325 4825);
FORCEPROP 2 LAST PATH I2
J 0
(11525 4875);
DISPLAY 1.021277 (11525 4875);
PAINT ORANGE (11525 4875);
DISPLAY INVISIBLE (11525 4875);
FORCEPROP 1 LAST OFFPAGE TRUE
J 0
(11650 4700);
PAINT GREEN (11650 4700);
DISPLAY INVISIBLE (11650 4700);
FORCEPROP 1 LAST COMMENT_BODY TRUE
J 0
(11280 4730);
DISPLAY 2.787234 (11280 4730);
PAINT PEACH (11280 4730);
DISPLAY INVISIBLE (11280 4730);
FORCEADD CAP_A..1
(7025 4550);
FORCEPROP 1 LASTPIN (7025 4450) $PN 2
J 0
(7035 4430);
DISPLAY 0.617021 (7035 4430);
PAINT WHITE (7035 4430);
FORCEPROP 1 LAST TOLERANCE 10%
J 0
(7075 4500);
DISPLAY 0.617021 (7075 4500);
PAINT SKYBLUE (7075 4500);
FORCEPROP 1 LAST VOLTAGE 16V
J 0
(7075 4550);
DISPLAY 0.617021 (7075 4550);
PAINT SKYBLUE (7075 4550);
FORCEPROP 1 LAST MATERIAL X7R
J 0
(7075 4450);
DISPLAY 0.617021 (7075 4450);
PAINT SKYBLUE (7075 4450);
FORCEPROP 1 LAST PACK_TYPE 0402V
J 0
(7075 4350);
DISPLAY 0.617021 (7075 4350);
PAINT SKYBLUE (7075 4350);
FORCEPROP 1 LAST PART_NUMBER A36096-030
J 0
(7075 4400);
DISPLAY 0.617021 (7075 4400);
PAINT BLUE (7075 4400);
FORCEPROP 1 LASTPIN (7025 4650) $PN 1
J 0
(7035 4630);
DISPLAY 0.617021 (7035 4630);
PAINT WHITE (7035 4630);
FORCEPROP 1 LAST VALUE 0.1UF
J 0
(7075 4600);
DISPLAY 0.617021 (7075 4600);
PAINT SKYBLUE (7075 4600);
FORCEPROP 1 LAST LOCATION C7A39
J 0
(7075 4650);
DISPLAY 0.617021 (7075 4650);
PAINT AQUA (7075 4650);
FORCEPROP 1 LAST PATH I20
J 0
(7075 4700);
DISPLAY 0.978723 (7075 4700);
PAINT WHITE (7075 4700);
DISPLAY INVISIBLE (7075 4700);
FORCEPROP 2 LAST ROOM PVNN_PCH_STBY
J 0
(7075 4700);
DISPLAY 2.212766 (7075 4700);
PAINT WHITE (7075 4700);
DISPLAY INVISIBLE (7075 4700);
FORCEPROP 2 LAST CDS_SEC 1
J 0
(7075 4700);
PAINT ORANGE (7075 4700);
DISPLAY INVISIBLE (7075 4700);
FORCEPROP 2 LAST SEC_TYPE 0402V
J 0
(7075 4750);
DISPLAY 1.659574 (7075 4750);
PAINT ORANGE (7075 4750);
DISPLAY INVISIBLE (7075 4750);
FORCEPROP 2 LAST SEC 1
J 0
(7075 4750);
DISPLAY 1.106383 (7075 4750);
PAINT MONO (7075 4750);
DISPLAY INVISIBLE (7075 4750);
FORCEPROP 2 LAST CDS_LIB dev_discrete
J 0
(7025 4550);
PAINT ORANGE (7025 4550);
DISPLAY INVISIBLE (7025 4550);
FORCEADD CAP..1
R 2
(6975 3850);
FORCEPROP 1 LASTPIN (6975 3950) $PN 1
J 2
(6965 3930);
DISPLAY 0.617021 (6965 3930);
PAINT ORANGE (6965 3930);
FORCEPROP 1 LAST PACK_TYPE 0402
J 2
(6925 3650);
DISPLAY 0.617021 (6925 3650);
PAINT SKYBLUE (6925 3650);
FORCEPROP 1 LASTPIN (6975 3750) $PN 2
J 2
(6965 3730);
DISPLAY 0.617021 (6965 3730);
PAINT ORANGE (6965 3730);
FORCEPROP 1 LAST VOLTAGE 16V
J 2
(6925 3850);
DISPLAY 0.617021 (6925 3850);
PAINT SKYBLUE (6925 3850);
FORCEPROP 1 LAST TOLERANCE 10%
J 2
(6925 3800);
DISPLAY 0.617021 (6925 3800);
PAINT SKYBLUE (6925 3800);
FORCEPROP 1 LAST PART_NUMBER A36096-104
J 2
(6925 3700);
DISPLAY 0.617021 (6925 3700);
PAINT BLUE (6925 3700);
FORCEPROP 1 LAST LOCATION C7A43
J 2
(6925 3950);
DISPLAY 0.617021 (6925 3950);
PAINT AQUA (6925 3950);
FORCEPROP 1 LAST VALUE 0.220UF
J 2
(6925 3900);
DISPLAY 0.617021 (6925 3900);
PAINT SKYBLUE (6925 3900);
FORCEPROP 1 LAST MATERIAL X7R
J 2
(6925 3750);
DISPLAY 0.617021 (6925 3750);
PAINT SKYBLUE (6925 3750);
FORCEPROP 2 LAST ROOM PVNN_PCH_STBY
J 0
(6925 4000);
DISPLAY 2.212766 (6925 4000);
PAINT WHITE (6925 4000);
DISPLAY INVISIBLE (6925 4000);
FORCEPROP 1 LAST PATH I21
J 2
(6925 4000);
DISPLAY 0.978723 (6925 4000);
PAINT WHITE (6925 4000);
DISPLAY INVISIBLE (6925 4000);
FORCEPROP 2 LAST SEC 1
J 0
(6925 4050);
DISPLAY 0.680851 (6925 4050);
PAINT MONO (6925 4050);
DISPLAY INVISIBLE (6925 4050);
FORCEPROP 2 LAST SEC_TYPE 0402
J 0
(6925 4050);
DISPLAY 1.021277 (6925 4050);
PAINT ORANGE (6925 4050);
DISPLAY INVISIBLE (6925 4050);
FORCEPROP 0 LAST SPOF TRUE
J 0
(6925 4050);
DISPLAY 1.021277 (6925 4050);
PAINT ORANGE (6925 4050);
DISPLAY INVISIBLE (6925 4050);
FORCEPROP 2 LAST CDS_LIB mstr_discrete
J 0
(6975 3850);
PAINT ORANGE (6975 3850);
DISPLAY INVISIBLE (6975 3850);
FORCEADD CAP..1
(6775 4500);
FORCEPROP 1 LAST VOLTAGE 16V
J 0
(6825 4500);
DISPLAY 0.617021 (6825 4500);
PAINT SKYBLUE (6825 4500);
FORCEPROP 1 LAST MATERIAL X6S
J 0
(6825 4400);
DISPLAY 0.617021 (6825 4400);
PAINT SKYBLUE (6825 4400);
FORCEPROP 1 LAST LOCATION C7A7
J 0
(6825 4600);
DISPLAY 0.617021 (6825 4600);
PAINT AQUA (6825 4600);
FORCEPROP 1 LASTPIN (6775 4600) $PN 1
J 0
(6785 4580);
DISPLAY 0.617021 (6785 4580);
PAINT WHITE (6785 4580);
FORCEPROP 1 LASTPIN (6775 4400) $PN 2
J 0
(6785 4380);
DISPLAY 0.617021 (6785 4380);
PAINT WHITE (6785 4380);
FORCEPROP 1 LAST PART_NUMBER D97712-011
J 0
(6825 4350);
DISPLAY 0.617021 (6825 4350);
PAINT BLUE (6825 4350);
FORCEPROP 1 LAST VALUE 1.0UF
J 0
(6825 4550);
DISPLAY 0.617021 (6825 4550);
PAINT SKYBLUE (6825 4550);
FORCEPROP 1 LAST PACK_TYPE 0402
J 0
(6825 4300);
DISPLAY 0.617021 (6825 4300);
PAINT SKYBLUE (6825 4300);
FORCEPROP 1 LAST TOLERANCE 10%
J 0
(6825 4450);
DISPLAY 0.617021 (6825 4450);
PAINT SKYBLUE (6825 4450);
FORCEPROP 2 LAST CDS_LIB mstr_discrete
J 0
(6775 4500);
DISPLAY 1.617021 (6775 4500);
PAINT ORANGE (6775 4500);
DISPLAY INVISIBLE (6775 4500);
FORCEPROP 2 LAST CDS_LOCATION C7A7
J 0
(6825 4600);
DISPLAY 0.617021 (6825 4600);
PAINT AQUA (6825 4600);
DISPLAY INVISIBLE (6825 4600);
FORCEPROP 2 LAST ROOM PVNN_PCH_STBY
J 0
(6825 4650);
DISPLAY 2.212766 (6825 4650);
PAINT WHITE (6825 4650);
DISPLAY INVISIBLE (6825 4650);
FORCEPROP 1 LAST PATH I22
J 0
(6825 4650);
DISPLAY 0.978723 (6825 4650);
PAINT WHITE (6825 4650);
DISPLAY INVISIBLE (6825 4650);
FORCEPROP 2 LAST SEC 1
J 0
(6825 4700);
DISPLAY 1.106383 (6825 4700);
PAINT MONO (6825 4700);
DISPLAY INVISIBLE (6825 4700);
FORCEPROP 2 LAST SEC_TYPE 0402
J 0
(6825 4700);
DISPLAY 1.659574 (6825 4700);
PAINT ORANGE (6825 4700);
DISPLAY INVISIBLE (6825 4700);
FORCEADD CAP..1
(6525 4550);
FORCEPROP 1 LASTPIN (6525 4450) $PN 2
J 0
(6535 4430);
DISPLAY 0.617021 (6535 4430);
PAINT WHITE (6535 4430);
FORCEPROP 1 LASTPIN (6525 4650) $PN 1
J 0
(6535 4630);
DISPLAY 0.617021 (6535 4630);
PAINT WHITE (6535 4630);
FORCEPROP 1 LAST LOCATION C3L12
J 0
(6575 4650);
DISPLAY 0.617021 (6575 4650);
PAINT AQUA (6575 4650);
FORCEPROP 1 LAST VALUE 10UF
J 0
(6575 4600);
DISPLAY 0.617021 (6575 4600);
PAINT SKYBLUE (6575 4600);
FORCEPROP 1 LAST PACK_TYPE 0805
J 0
(6575 4350);
DISPLAY 0.617021 (6575 4350);
PAINT SKYBLUE (6575 4350);
FORCEPROP 1 LAST TOLERANCE 10%
J 0
(6575 4500);
DISPLAY 0.617021 (6575 4500);
PAINT SKYBLUE (6575 4500);
FORCEPROP 1 LAST VOLTAGE 16V
J 0
(6575 4550);
DISPLAY 0.617021 (6575 4550);
PAINT SKYBLUE (6575 4550);
FORCEPROP 1 LAST MATERIAL X6S
J 0
(6575 4450);
DISPLAY 0.617021 (6575 4450);
PAINT SKYBLUE (6575 4450);
FORCEPROP 1 LAST PART_NUMBER C95333-007
J 0
(6575 4400);
DISPLAY 0.617021 (6575 4400);
PAINT BLUE (6575 4400);
FORCEPROP 2 LAST CDS_LIB mstr_discrete
J 0
(6525 4550);
DISPLAY 1.617021 (6525 4550);
PAINT ORANGE (6525 4550);
DISPLAY INVISIBLE (6525 4550);
FORCEPROP 2 LAST ROOM PVNN_PCH_STBY
J 0
(6575 4700);
DISPLAY 2.212766 (6575 4700);
PAINT WHITE (6575 4700);
DISPLAY INVISIBLE (6575 4700);
FORCEPROP 1 LAST PATH I23
J 0
(6575 4700);
DISPLAY 0.978723 (6575 4700);
PAINT WHITE (6575 4700);
DISPLAY INVISIBLE (6575 4700);
FORCEPROP 2 LAST CDS_LOCATION C3L12
J 0
(6575 4650);
DISPLAY 0.617021 (6575 4650);
PAINT AQUA (6575 4650);
DISPLAY INVISIBLE (6575 4650);
FORCEPROP 2 LAST SEC 1
J 0
(6575 4750);
DISPLAY 1.106383 (6575 4750);
PAINT MONO (6575 4750);
DISPLAY INVISIBLE (6575 4750);
FORCEPROP 2 LAST SEC_TYPE 0805
J 0
(6575 4750);
DISPLAY 1.659574 (6575 4750);
PAINT ORANGE (6575 4750);
DISPLAY INVISIBLE (6575 4750);
FORCEADD CAP..1
(6275 4500);
FORCEPROP 1 LAST TOLERANCE 10%
J 0
(6325 4450);
DISPLAY 0.617021 (6325 4450);
PAINT SKYBLUE (6325 4450);
FORCEPROP 1 LASTPIN (6275 4400) $PN 2
J 0
(6285 4380);
DISPLAY 0.617021 (6285 4380);
PAINT WHITE (6285 4380);
FORCEPROP 1 LAST VALUE 10UF
J 0
(6325 4550);
DISPLAY 0.617021 (6325 4550);
PAINT SKYBLUE (6325 4550);
FORCEPROP 1 LAST PACK_TYPE 0805
J 0
(6325 4300);
DISPLAY 0.617021 (6325 4300);
PAINT SKYBLUE (6325 4300);
FORCEPROP 1 LAST VOLTAGE 16V
J 0
(6325 4500);
DISPLAY 0.617021 (6325 4500);
PAINT SKYBLUE (6325 4500);
FORCEPROP 1 LAST MATERIAL X6S
J 0
(6325 4400);
DISPLAY 0.617021 (6325 4400);
PAINT SKYBLUE (6325 4400);
FORCEPROP 1 LAST LOCATION C3L11
J 0
(6325 4600);
DISPLAY 0.617021 (6325 4600);
PAINT AQUA (6325 4600);
FORCEPROP 1 LASTPIN (6275 4600) $PN 1
J 0
(6285 4580);
DISPLAY 0.617021 (6285 4580);
PAINT WHITE (6285 4580);
FORCEPROP 1 LAST PART_NUMBER C95333-007
J 0
(6325 4350);
DISPLAY 0.617021 (6325 4350);
PAINT BLUE (6325 4350);
FORCEPROP 2 LAST CDS_LIB mstr_discrete
J 0
(6275 4500);
DISPLAY 1.617021 (6275 4500);
PAINT ORANGE (6275 4500);
DISPLAY INVISIBLE (6275 4500);
FORCEPROP 2 LAST CDS_LOCATION C3L11
J 0
(6325 4600);
DISPLAY 0.617021 (6325 4600);
PAINT AQUA (6325 4600);
DISPLAY INVISIBLE (6325 4600);
FORCEPROP 2 LAST ROOM PVNN_PCH_STBY
J 0
(6325 4650);
DISPLAY 2.212766 (6325 4650);
PAINT WHITE (6325 4650);
DISPLAY INVISIBLE (6325 4650);
FORCEPROP 1 LAST PATH I24
J 0
(6325 4650);
DISPLAY 0.978723 (6325 4650);
PAINT WHITE (6325 4650);
DISPLAY INVISIBLE (6325 4650);
FORCEPROP 2 LAST SEC 1
J 0
(6325 4700);
DISPLAY 1.106383 (6325 4700);
PAINT MONO (6325 4700);
DISPLAY INVISIBLE (6325 4700);
FORCEPROP 2 LAST SEC_TYPE 0805
J 0
(6325 4700);
DISPLAY 1.659574 (6325 4700);
PAINT ORANGE (6325 4700);
DISPLAY INVISIBLE (6325 4700);
FORCEADD OFFPAGE..1
(6550 4175);
FORCEPROP 2 LAST $XR0 235 
J 0
(6298 4175);
DISPLAY 0.638298 (6298 4175);
PAINT MONO (6298 4175);
FORCEPROP 2 LAST ROOM PVCCIO_CPU0
J 0
(6150 4250);
DISPLAY 3.127660 (6150 4250);
PAINT WHITE (6150 4250);
DISPLAY INVISIBLE (6150 4250);
FORCEPROP 2 LAST PATH I25
J 0
(6300 4225);
DISPLAY 1.021277 (6300 4225);
PAINT ORANGE (6300 4225);
DISPLAY INVISIBLE (6300 4225);
FORCEPROP 2 LAST BOM_COST PROC_VRD_PVCCIO_CPU0
J 0
(6300 4225);
DISPLAY 2.340426 (6300 4225);
PAINT WHITE (6300 4225);
DISPLAY INVISIBLE (6300 4225);
FORCEPROP 2 LAST CDS_LIB mstr_standard
J 0
(6550 4175);
DISPLAY 1.617021 (6550 4175);
PAINT ORANGE (6550 4175);
DISPLAY INVISIBLE (6550 4175);
FORCEPROP 1 LAST OFFPAGE TRUE
J 0
(6875 4050);
PAINT GREEN (6875 4050);
DISPLAY INVISIBLE (6875 4050);
FORCEPROP 1 LAST COMMENT_BODY TRUE
J 0
(6675 4075);
DISPLAY 2.723404 (6675 4075);
PAINT PEACH (6675 4075);
DISPLAY INVISIBLE (6675 4075);
FORCEADD CAP..1
(6000 4550);
FORCEPROP 1 LAST TOLERANCE 10%
J 0
(6050 4500);
DISPLAY 0.617021 (6050 4500);
PAINT SKYBLUE (6050 4500);
FORCEPROP 1 LAST VALUE 10UF
J 0
(6050 4600);
DISPLAY 0.617021 (6050 4600);
PAINT SKYBLUE (6050 4600);
FORCEPROP 1 LAST VOLTAGE 16V
J 0
(6050 4550);
DISPLAY 0.617021 (6050 4550);
PAINT SKYBLUE (6050 4550);
FORCEPROP 1 LASTPIN (6000 4650) $PN 1
J 0
(6010 4630);
DISPLAY 0.617021 (6010 4630);
PAINT WHITE (6010 4630);
FORCEPROP 1 LASTPIN (6000 4450) $PN 2
J 0
(6010 4430);
DISPLAY 0.617021 (6010 4430);
PAINT WHITE (6010 4430);
FORCEPROP 1 LAST MATERIAL X6S
J 0
(6050 4450);
DISPLAY 0.617021 (6050 4450);
PAINT SKYBLUE (6050 4450);
FORCEPROP 1 LAST PACK_TYPE 0805
J 0
(6050 4350);
DISPLAY 0.617021 (6050 4350);
PAINT SKYBLUE (6050 4350);
FORCEPROP 1 LAST PART_NUMBER C95333-007
J 0
(6050 4400);
DISPLAY 0.617021 (6050 4400);
PAINT BLUE (6050 4400);
FORCEPROP 1 LAST LOCATION C3L8
J 0
(6050 4650);
DISPLAY 0.617021 (6050 4650);
PAINT AQUA (6050 4650);
FORCEPROP 2 LAST ROOM PVNN_PCH_STBY
J 0
(6050 4700);
DISPLAY 2.212766 (6050 4700);
PAINT WHITE (6050 4700);
DISPLAY INVISIBLE (6050 4700);
FORCEPROP 2 LAST SEC 1
J 0
(6050 4750);
DISPLAY 1.106383 (6050 4750);
PAINT MONO (6050 4750);
DISPLAY INVISIBLE (6050 4750);
FORCEPROP 2 LAST SEC_TYPE 0805
J 0
(6050 4750);
DISPLAY 1.659574 (6050 4750);
PAINT ORANGE (6050 4750);
DISPLAY INVISIBLE (6050 4750);
FORCEPROP 1 LAST PATH I26
J 0
(6050 4700);
DISPLAY 0.978723 (6050 4700);
PAINT WHITE (6050 4700);
DISPLAY INVISIBLE (6050 4700);
FORCEPROP 2 LAST CDS_LOCATION C3L8
J 0
(6050 4650);
DISPLAY 0.617021 (6050 4650);
PAINT AQUA (6050 4650);
DISPLAY INVISIBLE (6050 4650);
FORCEPROP 2 LAST CDS_LIB mstr_discrete
J 0
(6000 4550);
DISPLAY 1.617021 (6000 4550);
PAINT ORANGE (6000 4550);
DISPLAY INVISIBLE (6000 4550);
FORCEADD GND..1
(6000 4150);
FORCEPROP 3 LASTPIN (6000 4200) SIG_NAME GND\g
J 0
(6010 4210);
DISPLAY 0.659574 (6010 4210);
PAINT MONO (6010 4210);
DISPLAY INVISIBLE (6010 4210);
FORCEPROP 1 LAST HDL_POWER GND
J 0
(6000 4300);
DISPLAY 2.787234 (6000 4300);
PAINT GREEN (6000 4300);
DISPLAY INVISIBLE (6000 4300);
FORCEPROP 1 LAST BODY_TYPE PLUMBING
J 0
(5955 4107);
DISPLAY 0.340426 (5955 4107);
PAINT GREEN (5955 4107);
DISPLAY INVISIBLE (5955 4107);
FORCEPROP 2 LAST BOM_COST PROC_VRD_PVCCIO_CPU0
J 0
(5625 4225);
DISPLAY 2.340426 (5625 4225);
PAINT WHITE (5625 4225);
DISPLAY INVISIBLE (5625 4225);
FORCEPROP 2 LAST ROOM PVCCIO_CPU0
J 0
(5450 4225);
DISPLAY 3.127660 (5450 4225);
PAINT WHITE (5450 4225);
DISPLAY INVISIBLE (5450 4225);
FORCEPROP 1 LAST PATH I27
J 0
(6075 4150);
DISPLAY 0.872340 (6075 4150);
PAINT AQUA (6075 4150);
DISPLAY INVISIBLE (6075 4150);
FORCEPROP 2 LAST CDS_LIB mstr_symbols
J 0
(6000 4150);
DISPLAY 1.617021 (6000 4150);
PAINT ORANGE (6000 4150);
DISPLAY INVISIBLE (6000 4150);
FORCEPROP 1 LAST SIZE 1B
J 0
(6075 4100);
DISPLAY 2.787234 (6075 4100);
PAINT GREEN (6075 4100);
DISPLAY INVISIBLE (6075 4100);
FORCEPROP 1 LAST VOLTAGE 0.0V
J 0
(5955 4107);
DISPLAY 0.340426 (5955 4107);
PAINT SKYBLUE (5955 4107);
DISPLAY INVISIBLE (5955 4107);
FORCEADD GND..1
(6025 2300);
FORCEPROP 3 LASTPIN (6025 2350) SIG_NAME GND\g
J 0
(6035 2360);
DISPLAY 0.659574 (6035 2360);
PAINT MONO (6035 2360);
DISPLAY INVISIBLE (6035 2360);
FORCEPROP 1 LAST SIZE 1B
J 0
(6100 2250);
DISPLAY 2.787234 (6100 2250);
PAINT GREEN (6100 2250);
DISPLAY INVISIBLE (6100 2250);
FORCEPROP 1 LAST PATH I28
J 0
(6100 2300);
DISPLAY 0.872340 (6100 2300);
PAINT AQUA (6100 2300);
DISPLAY INVISIBLE (6100 2300);
FORCEPROP 2 LAST CDS_LIB mstr_symbols
J 0
(6025 2300);
DISPLAY 1.617021 (6025 2300);
PAINT ORANGE (6025 2300);
DISPLAY INVISIBLE (6025 2300);
FORCEPROP 1 LAST VOLTAGE 0.0V
J 0
(5980 2257);
DISPLAY 0.340426 (5980 2257);
PAINT SKYBLUE (5980 2257);
DISPLAY INVISIBLE (5980 2257);
FORCEPROP 2 LAST BOM_COST PROC_VRD_PVCCIO_CPU0
J 0
(5650 2375);
DISPLAY 2.340426 (5650 2375);
PAINT WHITE (5650 2375);
DISPLAY INVISIBLE (5650 2375);
FORCEPROP 2 LAST ROOM PVCCIO_CPU0
J 0
(5475 2375);
DISPLAY 3.127660 (5475 2375);
PAINT WHITE (5475 2375);
DISPLAY INVISIBLE (5475 2375);
FORCEPROP 1 LAST BODY_TYPE PLUMBING
J 0
(5980 2257);
DISPLAY 0.340426 (5980 2257);
PAINT GREEN (5980 2257);
DISPLAY INVISIBLE (5980 2257);
FORCEPROP 1 LAST HDL_POWER GND
J 0
(6025 2450);
DISPLAY 2.787234 (6025 2450);
PAINT GREEN (6025 2450);
DISPLAY INVISIBLE (6025 2450);
FORCEADD CAP..1
(6025 2875);
FORCEPROP 1 LASTPIN (6025 2775) $PN 2
J 0
(6035 2780);
DISPLAY 0.617021 (6035 2780);
PAINT WHITE (6035 2780);
FORCEPROP 1 LAST PACK_TYPE 0805
J 0
(6075 2675);
DISPLAY 0.617021 (6075 2675);
PAINT SKYBLUE (6075 2675);
FORCEPROP 1 LAST VOLTAGE 16V
J 0
(6075 2875);
DISPLAY 0.617021 (6075 2875);
PAINT SKYBLUE (6075 2875);
FORCEPROP 1 LAST VALUE 10UF
J 0
(6075 2925);
DISPLAY 0.617021 (6075 2925);
PAINT SKYBLUE (6075 2925);
FORCEPROP 1 LAST LOCATION C3L9
J 0
(6075 2975);
DISPLAY 0.617021 (6075 2975);
PAINT AQUA (6075 2975);
FORCEPROP 1 LAST TOLERANCE 10%
J 0
(6075 2825);
DISPLAY 0.617021 (6075 2825);
PAINT SKYBLUE (6075 2825);
FORCEPROP 1 LASTPIN (6025 2975) $PN 1
J 0
(6035 2955);
DISPLAY 0.617021 (6035 2955);
PAINT WHITE (6035 2955);
FORCEPROP 1 LAST PART_NUMBER C95333-007
J 0
(6050 2725);
DISPLAY 0.617021 (6050 2725);
PAINT BLUE (6050 2725);
FORCEPROP 1 LAST MATERIAL X6S
J 0
(6075 2775);
DISPLAY 0.617021 (6075 2775);
PAINT SKYBLUE (6075 2775);
FORCEPROP 1 LAST PATH I29
J 0
(6075 3025);
DISPLAY 0.978723 (6075 3025);
PAINT WHITE (6075 3025);
DISPLAY INVISIBLE (6075 3025);
FORCEPROP 2 LAST SEC_TYPE 0805
J 0
(6075 3075);
DISPLAY 1.659574 (6075 3075);
PAINT ORANGE (6075 3075);
DISPLAY INVISIBLE (6075 3075);
FORCEPROP 2 LAST SEC 1
J 0
(6075 3075);
DISPLAY 1.106383 (6075 3075);
PAINT MONO (6075 3075);
DISPLAY INVISIBLE (6075 3075);
FORCEPROP 2 LAST CDS_LOCATION C3L9
J 0
(6075 2975);
DISPLAY 0.617021 (6075 2975);
PAINT AQUA (6075 2975);
DISPLAY INVISIBLE (6075 2975);
FORCEPROP 2 LAST ROOM P1V05_PCH_STBY_VR
J 0
(6075 3025);
DISPLAY 2.212766 (6075 3025);
PAINT WHITE (6075 3025);
DISPLAY INVISIBLE (6075 3025);
FORCEPROP 2 LAST CDS_LIB mstr_discrete
J 0
(6025 2875);
DISPLAY 1.617021 (6025 2875);
PAINT ORANGE (6025 2875);
DISPLAY INVISIBLE (6025 2875);
FORCEADD OFFPAGE..2
(11450 5150);
FORCEPROP 2 LAST $XR0 235 
J 0
(11639 5150);
DISPLAY 0.638298 (11639 5150);
PAINT MONO (11639 5150);
FORCEPROP 2 LAST ROOM PVCCIO_CPU0
J 0
(11050 5225);
DISPLAY 3.127660 (11050 5225);
PAINT WHITE (11050 5225);
DISPLAY INVISIBLE (11050 5225);
FORCEPROP 2 LAST BOM_COST PROC_VRD_PVCCIO_CPU0
J 0
(11650 5200);
DISPLAY 2.340426 (11650 5200);
PAINT WHITE (11650 5200);
DISPLAY INVISIBLE (11650 5200);
FORCEPROP 2 LAST CDS_LIB mstr_standard
J 0
(11450 5150);
DISPLAY 1.617021 (11450 5150);
PAINT ORANGE (11450 5150);
DISPLAY INVISIBLE (11450 5150);
FORCEPROP 2 LAST PATH I3
J 0
(11650 5200);
DISPLAY 1.021277 (11650 5200);
PAINT ORANGE (11650 5200);
DISPLAY INVISIBLE (11650 5200);
FORCEPROP 1 LAST OFFPAGE TRUE
J 0
(11775 5025);
PAINT GREEN (11775 5025);
DISPLAY INVISIBLE (11775 5025);
FORCEPROP 1 LAST COMMENT_BODY TRUE
J 0
(11405 5055);
DISPLAY 2.787234 (11405 5055);
PAINT PEACH (11405 5055);
DISPLAY INVISIBLE (11405 5055);
FORCEADD OFFPAGE..1
(6600 2425);
FORCEPROP 2 LAST $XR0 235 
J 0
(6348 2425);
DISPLAY 0.638298 (6348 2425);
PAINT MONO (6348 2425);
FORCEPROP 2 LAST ROOM PVCCIO_CPU0
J 0
(6200 2500);
DISPLAY 3.127660 (6200 2500);
PAINT WHITE (6200 2500);
DISPLAY INVISIBLE (6200 2500);
FORCEPROP 2 LAST BOM_COST PROC_VRD_PVCCIO_CPU0
J 0
(6350 2475);
DISPLAY 2.340426 (6350 2475);
PAINT WHITE (6350 2475);
DISPLAY INVISIBLE (6350 2475);
FORCEPROP 2 LAST PATH I30
J 0
(6350 2475);
DISPLAY 1.021277 (6350 2475);
PAINT ORANGE (6350 2475);
DISPLAY INVISIBLE (6350 2475);
FORCEPROP 2 LAST CDS_LIB mstr_standard
J 0
(6600 2425);
DISPLAY 1.617021 (6600 2425);
PAINT ORANGE (6600 2425);
DISPLAY INVISIBLE (6600 2425);
FORCEPROP 1 LAST OFFPAGE TRUE
J 0
(6925 2300);
PAINT GREEN (6925 2300);
DISPLAY INVISIBLE (6925 2300);
FORCEPROP 1 LAST COMMENT_BODY TRUE
J 0
(6725 2325);
DISPLAY 2.723404 (6725 2325);
PAINT PEACH (6725 2325);
DISPLAY INVISIBLE (6725 2325);
FORCEADD CAP..1
(6250 2800);
FORCEPROP 1 LAST TOLERANCE 10%
J 0
(6300 2750);
DISPLAY 0.617021 (6300 2750);
PAINT SKYBLUE (6300 2750);
FORCEPROP 1 LAST MATERIAL X6S
J 0
(6300 2700);
DISPLAY 0.617021 (6300 2700);
PAINT SKYBLUE (6300 2700);
FORCEPROP 1 LASTPIN (6250 2900) $PN 1
J 0
(6260 2880);
DISPLAY 0.617021 (6260 2880);
PAINT WHITE (6260 2880);
FORCEPROP 1 LASTPIN (6250 2700) $PN 2
J 0
(6260 2705);
DISPLAY 0.617021 (6260 2705);
PAINT WHITE (6260 2705);
FORCEPROP 1 LAST LOCATION C3L7
J 0
(6300 2900);
DISPLAY 0.617021 (6300 2900);
PAINT AQUA (6300 2900);
FORCEPROP 1 LAST VALUE 10UF
J 0
(6300 2850);
DISPLAY 0.617021 (6300 2850);
PAINT SKYBLUE (6300 2850);
FORCEPROP 1 LAST VOLTAGE 16V
J 0
(6300 2800);
DISPLAY 0.617021 (6300 2800);
PAINT SKYBLUE (6300 2800);
FORCEPROP 1 LAST PACK_TYPE 0805
J 0
(6300 2600);
DISPLAY 0.617021 (6300 2600);
PAINT SKYBLUE (6300 2600);
FORCEPROP 1 LAST PART_NUMBER C95333-007
J 0
(6275 2650);
DISPLAY 0.617021 (6275 2650);
PAINT BLUE (6275 2650);
FORCEPROP 2 LAST ROOM P1V05_PCH_STBY_VR
J 0
(6300 2950);
DISPLAY 2.212766 (6300 2950);
PAINT WHITE (6300 2950);
DISPLAY INVISIBLE (6300 2950);
FORCEPROP 2 LAST SEC 1
J 0
(6300 3000);
DISPLAY 1.106383 (6300 3000);
PAINT MONO (6300 3000);
DISPLAY INVISIBLE (6300 3000);
FORCEPROP 2 LAST SEC_TYPE 0805
J 0
(6300 3000);
DISPLAY 1.659574 (6300 3000);
PAINT ORANGE (6300 3000);
DISPLAY INVISIBLE (6300 3000);
FORCEPROP 2 LAST CDS_LOCATION C3L7
J 0
(6300 2900);
DISPLAY 0.617021 (6300 2900);
PAINT AQUA (6300 2900);
DISPLAY INVISIBLE (6300 2900);
FORCEPROP 1 LAST PATH I31
J 0
(6300 2950);
DISPLAY 0.978723 (6300 2950);
PAINT WHITE (6300 2950);
DISPLAY INVISIBLE (6300 2950);
FORCEPROP 2 LAST CDS_LIB mstr_discrete
J 0
(6250 2800);
DISPLAY 1.617021 (6250 2800);
PAINT ORANGE (6250 2800);
DISPLAY INVISIBLE (6250 2800);
FORCEADD CAP..1
(6475 2875);
FORCEPROP 1 LASTPIN (6475 2975) $PN 1
J 0
(6485 2955);
DISPLAY 0.617021 (6485 2955);
PAINT WHITE (6485 2955);
FORCEPROP 1 LAST MATERIAL X6S
J 0
(6525 2775);
DISPLAY 0.617021 (6525 2775);
PAINT SKYBLUE (6525 2775);
FORCEPROP 1 LAST VOLTAGE 16V
J 0
(6525 2875);
DISPLAY 0.617021 (6525 2875);
PAINT SKYBLUE (6525 2875);
FORCEPROP 1 LAST VALUE 10UF
J 0
(6525 2925);
DISPLAY 0.617021 (6525 2925);
PAINT SKYBLUE (6525 2925);
FORCEPROP 1 LAST PACK_TYPE 0805
J 0
(6525 2675);
DISPLAY 0.617021 (6525 2675);
PAINT SKYBLUE (6525 2675);
FORCEPROP 1 LASTPIN (6475 2775) $PN 2
J 0
(6485 2780);
DISPLAY 0.617021 (6485 2780);
PAINT WHITE (6485 2780);
FORCEPROP 1 LAST LOCATION C3L10
J 0
(6525 2975);
DISPLAY 0.617021 (6525 2975);
PAINT AQUA (6525 2975);
FORCEPROP 1 LAST TOLERANCE 10%
J 0
(6525 2825);
DISPLAY 0.617021 (6525 2825);
PAINT SKYBLUE (6525 2825);
FORCEPROP 1 LAST PART_NUMBER C95333-007
J 0
(6500 2725);
DISPLAY 0.617021 (6500 2725);
PAINT BLUE (6500 2725);
FORCEPROP 2 LAST CDS_LIB mstr_discrete
J 0
(6475 2875);
DISPLAY 1.617021 (6475 2875);
PAINT ORANGE (6475 2875);
DISPLAY INVISIBLE (6475 2875);
FORCEPROP 2 LAST ROOM P1V05_PCH_STBY_VR
J 0
(6525 3025);
DISPLAY 2.212766 (6525 3025);
PAINT WHITE (6525 3025);
DISPLAY INVISIBLE (6525 3025);
FORCEPROP 1 LAST PATH I32
J 0
(6525 3025);
DISPLAY 0.978723 (6525 3025);
PAINT WHITE (6525 3025);
DISPLAY INVISIBLE (6525 3025);
FORCEPROP 2 LAST CDS_LOCATION C3L10
J 0
(6525 2975);
DISPLAY 0.617021 (6525 2975);
PAINT AQUA (6525 2975);
DISPLAY INVISIBLE (6525 2975);
FORCEPROP 2 LAST SEC 1
J 0
(6525 3075);
DISPLAY 1.106383 (6525 3075);
PAINT MONO (6525 3075);
DISPLAY INVISIBLE (6525 3075);
FORCEPROP 2 LAST SEC_TYPE 0805
J 0
(6525 3075);
DISPLAY 1.659574 (6525 3075);
PAINT ORANGE (6525 3075);
DISPLAY INVISIBLE (6525 3075);
FORCEADD CAP..1
(6700 2800);
FORCEPROP 1 LAST MATERIAL X6S
J 0
(6750 2700);
DISPLAY 0.617021 (6750 2700);
PAINT SKYBLUE (6750 2700);
FORCEPROP 1 LAST TOLERANCE 10%
J 0
(6750 2750);
DISPLAY 0.617021 (6750 2750);
PAINT SKYBLUE (6750 2750);
FORCEPROP 1 LASTPIN (6700 2700) $PN 2
J 0
(6710 2705);
DISPLAY 0.617021 (6710 2705);
PAINT WHITE (6710 2705);
FORCEPROP 1 LASTPIN (6700 2900) $PN 1
J 0
(6710 2880);
DISPLAY 0.617021 (6710 2880);
PAINT WHITE (6710 2880);
FORCEPROP 1 LAST VOLTAGE 16V
J 0
(6750 2800);
DISPLAY 0.617021 (6750 2800);
PAINT SKYBLUE (6750 2800);
FORCEPROP 1 LAST VALUE 1.0UF
J 0
(6750 2850);
DISPLAY 0.617021 (6750 2850);
PAINT SKYBLUE (6750 2850);
FORCEPROP 1 LAST LOCATION C7A9
J 0
(6750 2900);
DISPLAY 0.617021 (6750 2900);
PAINT AQUA (6750 2900);
FORCEPROP 1 LAST PACK_TYPE 0402
J 0
(6750 2600);
DISPLAY 0.617021 (6750 2600);
PAINT SKYBLUE (6750 2600);
FORCEPROP 1 LAST PART_NUMBER D97712-011
J 0
(6725 2650);
DISPLAY 0.617021 (6725 2650);
PAINT BLUE (6725 2650);
FORCEPROP 2 LAST SEC_TYPE 0402
J 0
(6750 3000);
DISPLAY 1.659574 (6750 3000);
PAINT ORANGE (6750 3000);
DISPLAY INVISIBLE (6750 3000);
FORCEPROP 2 LAST ROOM P1V05_PCH_STBY_VR
J 0
(6750 2950);
DISPLAY 2.212766 (6750 2950);
PAINT WHITE (6750 2950);
DISPLAY INVISIBLE (6750 2950);
FORCEPROP 1 LAST PATH I33
J 0
(6750 2950);
DISPLAY 0.978723 (6750 2950);
PAINT WHITE (6750 2950);
DISPLAY INVISIBLE (6750 2950);
FORCEPROP 2 LAST CDS_LOCATION C7A9
J 0
(6750 2900);
DISPLAY 0.617021 (6750 2900);
PAINT AQUA (6750 2900);
DISPLAY INVISIBLE (6750 2900);
FORCEPROP 2 LAST SEC 1
J 0
(6750 3000);
DISPLAY 1.106383 (6750 3000);
PAINT MONO (6750 3000);
DISPLAY INVISIBLE (6750 3000);
FORCEPROP 2 LAST CDS_LIB mstr_discrete
J 0
(6700 2800);
DISPLAY 1.617021 (6700 2800);
PAINT ORANGE (6700 2800);
DISPLAY INVISIBLE (6700 2800);
FORCEADD CAP..1
R 2
(7050 2100);
FORCEPROP 1 LASTPIN (7050 2000) $PN 2
J 2
(7040 1980);
DISPLAY 0.617021 (7040 1980);
PAINT ORANGE (7040 1980);
FORCEPROP 1 LASTPIN (7050 2200) $PN 1
J 2
(7040 2180);
DISPLAY 0.617021 (7040 2180);
PAINT ORANGE (7040 2180);
FORCEPROP 1 LAST PACK_TYPE 0402
J 2
(7000 1900);
DISPLAY 0.617021 (7000 1900);
PAINT SKYBLUE (7000 1900);
FORCEPROP 1 LAST MATERIAL X7R
J 2
(7000 2000);
DISPLAY 0.617021 (7000 2000);
PAINT SKYBLUE (7000 2000);
FORCEPROP 1 LAST TOLERANCE 10%
J 2
(7000 2050);
DISPLAY 0.617021 (7000 2050);
PAINT SKYBLUE (7000 2050);
FORCEPROP 1 LAST VOLTAGE 16V
J 2
(7000 2100);
DISPLAY 0.617021 (7000 2100);
PAINT SKYBLUE (7000 2100);
FORCEPROP 1 LAST LOCATION C7A44
J 2
(7000 2200);
DISPLAY 0.617021 (7000 2200);
PAINT AQUA (7000 2200);
FORCEPROP 1 LAST PART_NUMBER A36096-104
J 2
(7000 1950);
DISPLAY 0.617021 (7000 1950);
PAINT BLUE (7000 1950);
FORCEPROP 1 LAST VALUE 0.220UF
J 2
(7000 2150);
DISPLAY 0.617021 (7000 2150);
PAINT SKYBLUE (7000 2150);
FORCEPROP 2 LAST ROOM P1V05_PCH_STBY_VR
J 0
(7000 2250);
DISPLAY 2.212766 (7000 2250);
PAINT WHITE (7000 2250);
DISPLAY INVISIBLE (7000 2250);
FORCEPROP 1 LAST PATH I34
J 2
(7000 2250);
DISPLAY 0.978723 (7000 2250);
PAINT WHITE (7000 2250);
DISPLAY INVISIBLE (7000 2250);
FORCEPROP 2 LAST SEC 1
J 0
(7000 2300);
DISPLAY 0.680851 (7000 2300);
PAINT MONO (7000 2300);
DISPLAY INVISIBLE (7000 2300);
FORCEPROP 2 LAST CDS_LIB mstr_discrete
J 0
(7050 2100);
PAINT ORANGE (7050 2100);
DISPLAY INVISIBLE (7050 2100);
FORCEPROP 0 LAST SPOF TRUE
J 0
(7000 2300);
DISPLAY 1.021277 (7000 2300);
PAINT ORANGE (7000 2300);
DISPLAY INVISIBLE (7000 2300);
FORCEPROP 2 LAST SEC_TYPE 0402
J 0
(7000 2300);
DISPLAY 1.021277 (7000 2300);
PAINT ORANGE (7000 2300);
DISPLAY INVISIBLE (7000 2300);
FORCEADD CAP_A..1
(6925 2875);
FORCEPROP 1 LASTPIN (6925 2975) $PN 1
J 0
(6935 2955);
DISPLAY 0.617021 (6935 2955);
PAINT WHITE (6935 2955);
FORCEPROP 1 LASTPIN (6925 2775) $PN 2
J 0
(6935 2780);
DISPLAY 0.617021 (6935 2780);
PAINT WHITE (6935 2780);
FORCEPROP 1 LAST MATERIAL X7R
J 0
(6975 2775);
DISPLAY 0.617021 (6975 2775);
PAINT SKYBLUE (6975 2775);
FORCEPROP 1 LAST TOLERANCE 10%
J 0
(6975 2825);
DISPLAY 0.617021 (6975 2825);
PAINT SKYBLUE (6975 2825);
FORCEPROP 1 LAST VOLTAGE 16V
J 0
(6975 2875);
DISPLAY 0.617021 (6975 2875);
PAINT SKYBLUE (6975 2875);
FORCEPROP 1 LAST VALUE 0.1UF
J 0
(6975 2925);
DISPLAY 0.617021 (6975 2925);
PAINT SKYBLUE (6975 2925);
FORCEPROP 1 LAST LOCATION C7A40
J 0
(6975 2975);
DISPLAY 0.617021 (6975 2975);
PAINT AQUA (6975 2975);
FORCEPROP 1 LAST PACK_TYPE 0402V
J 0
(6975 2675);
DISPLAY 0.617021 (6975 2675);
PAINT SKYBLUE (6975 2675);
FORCEPROP 1 LAST PART_NUMBER A36096-030
J 0
(6950 2725);
DISPLAY 0.617021 (6950 2725);
PAINT BLUE (6950 2725);
FORCEPROP 2 LAST CDS_LIB dev_discrete
J 0
(6925 2875);
PAINT ORANGE (6925 2875);
DISPLAY INVISIBLE (6925 2875);
FORCEPROP 2 LAST CDS_SEC 1
J 0
(6975 3025);
PAINT ORANGE (6975 3025);
DISPLAY INVISIBLE (6975 3025);
FORCEPROP 1 LAST PATH I35
J 0
(6975 3025);
DISPLAY 0.978723 (6975 3025);
PAINT WHITE (6975 3025);
DISPLAY INVISIBLE (6975 3025);
FORCEPROP 2 LAST ROOM P1V05_PCH_STBY_VR
J 0
(6975 3025);
DISPLAY 2.212766 (6975 3025);
PAINT WHITE (6975 3025);
DISPLAY INVISIBLE (6975 3025);
FORCEPROP 2 LAST SEC_TYPE 0402V
J 0
(6975 3075);
DISPLAY 1.659574 (6975 3075);
PAINT ORANGE (6975 3075);
DISPLAY INVISIBLE (6975 3075);
FORCEPROP 2 LAST SEC 1
J 0
(6975 3075);
DISPLAY 1.106383 (6975 3075);
PAINT MONO (6975 3075);
DISPLAY INVISIBLE (6975 3075);
FORCEADD CAP..1
(7175 2800);
FORCEPROP 1 LASTPIN (7175 2900) $PN 1
J 0
(7185 2880);
DISPLAY 0.617021 (7185 2880);
PAINT WHITE (7185 2880);
FORCEPROP 1 LAST PACK_TYPE 0402
J 0
(7225 2600);
DISPLAY 0.617021 (7225 2600);
PAINT SKYBLUE (7225 2600);
FORCEPROP 1 LASTPIN (7175 2700) $PN 2
J 0
(7185 2705);
DISPLAY 0.617021 (7185 2705);
PAINT WHITE (7185 2705);
FORCEPROP 1 LAST VALUE 1.0UF
J 0
(7225 2850);
DISPLAY 0.617021 (7225 2850);
PAINT SKYBLUE (7225 2850);
FORCEPROP 1 LAST VOLTAGE 16V
J 0
(7225 2800);
DISPLAY 0.617021 (7225 2800);
PAINT SKYBLUE (7225 2800);
FORCEPROP 1 LAST TOLERANCE 10%
J 0
(7225 2750);
DISPLAY 0.617021 (7225 2750);
PAINT SKYBLUE (7225 2750);
FORCEPROP 1 LAST MATERIAL X6S
J 0
(7225 2700);
DISPLAY 0.617021 (7225 2700);
PAINT SKYBLUE (7225 2700);
FORCEPROP 1 LAST PART_NUMBER D97712-011
J 0
(7200 2650);
DISPLAY 0.617021 (7200 2650);
PAINT BLUE (7200 2650);
FORCEPROP 1 LAST LOCATION C7A10
J 0
(7225 2900);
DISPLAY 0.617021 (7225 2900);
PAINT AQUA (7225 2900);
FORCEPROP 2 LAST ROOM P1V05_PCH_STBY_VR
J 0
(7225 2950);
DISPLAY 2.212766 (7225 2950);
PAINT WHITE (7225 2950);
DISPLAY INVISIBLE (7225 2950);
FORCEPROP 2 LAST SEC 1
J 0
(7225 3000);
DISPLAY 1.106383 (7225 3000);
PAINT MONO (7225 3000);
DISPLAY INVISIBLE (7225 3000);
FORCEPROP 2 LAST SEC_TYPE 0402
J 0
(7225 3000);
DISPLAY 1.659574 (7225 3000);
PAINT ORANGE (7225 3000);
DISPLAY INVISIBLE (7225 3000);
FORCEPROP 2 LAST CDS_LOCATION C7A10
J 0
(7225 2900);
DISPLAY 0.617021 (7225 2900);
PAINT AQUA (7225 2900);
DISPLAY INVISIBLE (7225 2900);
FORCEPROP 1 LAST PATH I36
J 0
(7225 2950);
DISPLAY 0.978723 (7225 2950);
PAINT WHITE (7225 2950);
DISPLAY INVISIBLE (7225 2950);
FORCEPROP 2 LAST CDS_LIB mstr_discrete
J 0
(7175 2800);
DISPLAY 1.617021 (7175 2800);
PAINT ORANGE (7175 2800);
DISPLAY INVISIBLE (7175 2800);
FORCEADD CAP..1
(8000 2875);
FORCEPROP 1 LAST LOCATION C7A41
J 0
(8050 2975);
DISPLAY 0.617021 (8050 2975);
PAINT AQUA (8050 2975);
FORCEPROP 1 LASTPIN (8000 2975) $PN 1
J 0
(8010 2955);
DISPLAY 0.617021 (8010 2955);
PAINT WHITE (8010 2955);
FORCEPROP 1 LAST PACK_TYPE 0402
J 0
(8050 2675);
DISPLAY 0.617021 (8050 2675);
PAINT SKYBLUE (8050 2675);
FORCEPROP 1 LAST PART_NUMBER A36096-155
J 0
(8050 2725);
DISPLAY 0.617021 (8050 2725);
PAINT BLUE (8050 2725);
FORCEPROP 1 LAST TOLERANCE 10%
J 0
(8050 2825);
DISPLAY 0.617021 (8050 2825);
PAINT SKYBLUE (8050 2825);
FORCEPROP 1 LAST MATERIAL X7R
J 0
(8050 2775);
DISPLAY 0.617021 (8050 2775);
PAINT SKYBLUE (8050 2775);
FORCEPROP 1 LASTPIN (8000 2775) $PN 2
J 0
(8010 2755);
DISPLAY 0.617021 (8010 2755);
PAINT WHITE (8010 2755);
FORCEPROP 1 LAST VOLTAGE 16V
J 0
(8050 2875);
DISPLAY 0.617021 (8050 2875);
PAINT SKYBLUE (8050 2875);
FORCEPROP 1 LAST VALUE 0.22UF
J 0
(8050 2925);
DISPLAY 0.617021 (8050 2925);
PAINT SKYBLUE (8050 2925);
FORCEPROP 2 LAST ROOM P1V05_PCH_STBY_VR
J 0
(8050 3025);
DISPLAY 2.212766 (8050 3025);
PAINT WHITE (8050 3025);
DISPLAY INVISIBLE (8050 3025);
FORCEPROP 2 LAST SEC 1
J 0
(8050 3075);
DISPLAY 1.106383 (8050 3075);
PAINT MONO (8050 3075);
DISPLAY INVISIBLE (8050 3075);
FORCEPROP 2 LAST SEC_TYPE 0402
J 0
(8050 3075);
DISPLAY 1.659574 (8050 3075);
PAINT ORANGE (8050 3075);
DISPLAY INVISIBLE (8050 3075);
FORCEPROP 1 LAST PATH I39
J 0
(8050 3025);
DISPLAY 0.978723 (8050 3025);
PAINT WHITE (8050 3025);
DISPLAY INVISIBLE (8050 3025);
FORCEPROP 2 LAST CDS_LIB mstr_discrete
J 0
(8000 2875);
DISPLAY 1.617021 (8000 2875);
PAINT ORANGE (8000 2875);
DISPLAY INVISIBLE (8000 2875);
FORCEADD P5V_STBY..1
(8525 3425);
FORCEPROP 3 LASTPIN (8525 3375) SIG_NAME P5V_STBY\g
J 0
(8535 3385);
DISPLAY 0.659574 (8535 3385);
PAINT MONO (8535 3385);
DISPLAY INVISIBLE (8535 3385);
FORCEPROP 2 LAST CDS_LIB mstr_symbols
J 0
(8525 3425);
PAINT ORANGE (8525 3425);
DISPLAY INVISIBLE (8525 3425);
FORCEPROP 1 LAST PATH I42
J 0
(8570 3427);
DISPLAY 0.340426 (8570 3427);
PAINT GREEN (8570 3427);
DISPLAY INVISIBLE (8570 3427);
FORCEPROP 1 LAST VOLTAGE 5.0V
J 0
(8480 3382);
DISPLAY 0.340426 (8480 3382);
PAINT SKYBLUE (8480 3382);
DISPLAY INVISIBLE (8480 3382);
FORCEPROP 1 LAST SIZE 1B
J 0
(8570 3447);
DISPLAY 0.340426 (8570 3447);
PAINT GREEN (8570 3447);
DISPLAY INVISIBLE (8570 3447);
FORCEPROP 1 LAST BODY_TYPE PLUMBING
J 0
(8480 3382);
DISPLAY 0.340426 (8480 3382);
PAINT GREEN (8480 3382);
DISPLAY INVISIBLE (8480 3382);
FORCEPROP 1 LAST HDL_POWER P5V_STBY
J 0
(8225 3300);
DISPLAY 0.872340 (8225 3300);
PAINT ORANGE (8225 3300);
DISPLAY INVISIBLE (8225 3300);
FORCEADD GND..1
(10450 1875);
FORCEPROP 3 LASTPIN (10450 1925) SIG_NAME GND\g
J 0
(10460 1935);
DISPLAY 0.659574 (10460 1935);
PAINT MONO (10460 1935);
DISPLAY INVISIBLE (10460 1935);
FORCEPROP 2 LAST CDS_LIB mstr_symbols
J 0
(10450 1875);
DISPLAY 1.617021 (10450 1875);
PAINT ORANGE (10450 1875);
DISPLAY INVISIBLE (10450 1875);
FORCEPROP 1 LAST SIZE 1B
J 0
(10525 1825);
DISPLAY 2.787234 (10525 1825);
PAINT GREEN (10525 1825);
DISPLAY INVISIBLE (10525 1825);
FORCEPROP 1 LAST PATH I44
J 0
(10525 1875);
DISPLAY 0.872340 (10525 1875);
PAINT AQUA (10525 1875);
DISPLAY INVISIBLE (10525 1875);
FORCEPROP 1 LAST VOLTAGE 0.0V
J 0
(10405 1832);
DISPLAY 0.340426 (10405 1832);
PAINT SKYBLUE (10405 1832);
DISPLAY INVISIBLE (10405 1832);
FORCEPROP 2 LAST ROOM PVCCIO_CPU0
J 0
(9900 1950);
DISPLAY 3.127660 (9900 1950);
PAINT WHITE (9900 1950);
DISPLAY INVISIBLE (9900 1950);
FORCEPROP 2 LAST BOM_COST PROC_VRD_PVCCIO_CPU0
J 0
(10075 1950);
DISPLAY 2.340426 (10075 1950);
PAINT WHITE (10075 1950);
DISPLAY INVISIBLE (10075 1950);
FORCEPROP 1 LAST BODY_TYPE PLUMBING
J 0
(10405 1832);
DISPLAY 0.340426 (10405 1832);
PAINT GREEN (10405 1832);
DISPLAY INVISIBLE (10405 1832);
FORCEPROP 1 LAST HDL_POWER GND
J 0
(10450 2025);
DISPLAY 2.787234 (10450 2025);
PAINT GREEN (10450 2025);
DISPLAY INVISIBLE (10450 2025);
FORCEADD CAP..1
(11650 2050);
FORCEPROP 1 LAST PART_NUMBER C95333-002
J 0
(11700 1900);
DISPLAY 0.617021 (11700 1900);
PAINT BLUE (11700 1900);
FORCEPROP 1 LAST LOCATION C7A42
J 0
(11700 2150);
DISPLAY 0.617021 (11700 2150);
PAINT AQUA (11700 2150);
FORCEPROP 1 LAST VALUE 22UF
J 0
(11700 2100);
DISPLAY 0.617021 (11700 2100);
PAINT SKYBLUE (11700 2100);
FORCEPROP 1 LAST VOLTAGE 4V
J 0
(11700 2050);
DISPLAY 0.765957 (11700 2050);
PAINT SKYBLUE (11700 2050);
FORCEPROP 1 LAST TOLERANCE 20%
J 0
(11700 2000);
DISPLAY 0.617021 (11700 2000);
PAINT SKYBLUE (11700 2000);
FORCEPROP 1 LASTPIN (11650 1950) $PN 2
J 0
(11660 1930);
DISPLAY 0.617021 (11660 1930);
PAINT WHITE (11660 1930);
FORCEPROP 1 LASTPIN (11650 2150) $PN 1
J 0
(11660 2130);
DISPLAY 0.617021 (11660 2130);
PAINT WHITE (11660 2130);
FORCEPROP 1 LAST PACK_TYPE 0805LF
J 0
(11700 1850);
DISPLAY 0.617021 (11700 1850);
PAINT SKYBLUE (11700 1850);
FORCEPROP 1 LAST MATERIAL X6S
J 0
(11700 1950);
DISPLAY 0.617021 (11700 1950);
PAINT SKYBLUE (11700 1950);
FORCEPROP 2 LAST CDS_LIB mstr_discrete
J 0
(11650 2050);
DISPLAY 1.617021 (11650 2050);
PAINT ORANGE (11650 2050);
DISPLAY INVISIBLE (11650 2050);
FORCEPROP 1 LAST PATH I46
J 0
(11700 2200);
DISPLAY 0.978723 (11700 2200);
PAINT WHITE (11700 2200);
DISPLAY INVISIBLE (11700 2200);
FORCEPROP 2 LAST ROOM P1V05_PCH_STBY_VR
J 0
(11700 2200);
DISPLAY 2.340426 (11700 2200);
PAINT WHITE (11700 2200);
DISPLAY INVISIBLE (11700 2200);
FORCEPROP 2 LAST BOM_COST PROC_VRD_PVCCIO_CPU0
J 0
(11700 2200);
DISPLAY 2.340426 (11700 2200);
PAINT WHITE (11700 2200);
DISPLAY INVISIBLE (11700 2200);
FORCEPROP 2 LAST SEC_TYPE 0805LF
J 0
(11705 2250);
DISPLAY 1.659574 (11705 2250);
PAINT ORANGE (11705 2250);
DISPLAY INVISIBLE (11705 2250);
FORCEPROP 2 LAST SEC 1
J 0
(11705 2250);
DISPLAY 1.106383 (11705 2250);
PAINT MONO (11705 2250);
DISPLAY INVISIBLE (11705 2250);
FORCEPROP 2 LAST CDS_LOCATION C7A42
J 0
(11700 2150);
DISPLAY 0.617021 (11700 2150);
PAINT AQUA (11700 2150);
DISPLAY INVISIBLE (11700 2150);
FORCEADD GND..1
(11650 1825);
FORCEPROP 3 LASTPIN (11650 1875) SIG_NAME GND\g
J 0
(11660 1885);
DISPLAY 0.659574 (11660 1885);
PAINT MONO (11660 1885);
DISPLAY INVISIBLE (11660 1885);
FORCEPROP 2 LAST ROOM PVCCIO_CPU0
J 0
(11100 1900);
DISPLAY 3.127660 (11100 1900);
PAINT WHITE (11100 1900);
DISPLAY INVISIBLE (11100 1900);
FORCEPROP 2 LAST BOM_COST PROC_VRD_PVCCIO_CPU0
J 0
(11275 1900);
DISPLAY 2.340426 (11275 1900);
PAINT WHITE (11275 1900);
DISPLAY INVISIBLE (11275 1900);
FORCEPROP 1 LAST VOLTAGE 0.0V
J 0
(11605 1782);
DISPLAY 0.340426 (11605 1782);
PAINT SKYBLUE (11605 1782);
DISPLAY INVISIBLE (11605 1782);
FORCEPROP 2 LAST CDS_LIB mstr_symbols
J 0
(11650 1825);
DISPLAY 1.617021 (11650 1825);
PAINT ORANGE (11650 1825);
DISPLAY INVISIBLE (11650 1825);
FORCEPROP 1 LAST SIZE 1B
J 0
(11725 1775);
DISPLAY 2.787234 (11725 1775);
PAINT GREEN (11725 1775);
DISPLAY INVISIBLE (11725 1775);
FORCEPROP 1 LAST PATH I47
J 0
(11725 1825);
DISPLAY 0.872340 (11725 1825);
PAINT AQUA (11725 1825);
DISPLAY INVISIBLE (11725 1825);
FORCEPROP 1 LAST BODY_TYPE PLUMBING
J 0
(11605 1782);
DISPLAY 0.340426 (11605 1782);
PAINT GREEN (11605 1782);
DISPLAY INVISIBLE (11605 1782);
FORCEPROP 1 LAST HDL_POWER GND
J 0
(11650 1975);
DISPLAY 2.787234 (11650 1975);
PAINT GREEN (11650 1975);
DISPLAY INVISIBLE (11650 1975);
FORCEADD P1V05_PCH_STBY..1
(12700 2375);
FORCEPROP 3 LASTPIN (12700 2325) SIG_NAME P1V05_PCH_STBY\g
J 0
(12710 2335);
DISPLAY 0.659574 (12710 2335);
PAINT MONO (12710 2335);
DISPLAY INVISIBLE (12710 2335);
FORCEPROP 1 LAST VOLTAGE 1.05V
J 0
(12655 2332);
DISPLAY 0.340426 (12655 2332);
PAINT SKYBLUE (12655 2332);
DISPLAY INVISIBLE (12655 2332);
FORCEPROP 2 LAST CDS_LIB mstr_symbols
J 0
(12700 2375);
PAINT ORANGE (12700 2375);
DISPLAY INVISIBLE (12700 2375);
FORCEPROP 2 LAST BOM_COST PROC_VRD_PVCCIO_CPU0
J 0
(12700 2475);
DISPLAY 2.340426 (12700 2475);
PAINT WHITE (12700 2475);
DISPLAY INVISIBLE (12700 2475);
FORCEPROP 1 LAST PATH I48
J 0
(12750 2400);
DISPLAY 0.872340 (12750 2400);
PAINT AQUA (12750 2400);
DISPLAY INVISIBLE (12750 2400);
FORCEPROP 2 LAST ROOM PVCCIO_CPU0
J 0
(12700 2475);
DISPLAY 3.127660 (12700 2475);
PAINT WHITE (12700 2475);
DISPLAY INVISIBLE (12700 2475);
FORCEPROP 1 LAST BODY_TYPE PLUMBING
J 0
(12655 2332);
DISPLAY 0.340426 (12655 2332);
PAINT GREEN (12655 2332);
DISPLAY INVISIBLE (12655 2332);
FORCEPROP 1 LAST HDL_POWER P1V05_PCH_STBY
J 0
(12700 2425);
DISPLAY 0.872340 (12700 2425);
PAINT GREEN (12700 2425);
DISPLAY INVISIBLE (12700 2425);
FORCEADD OFFPAGE..2
(12100 3250);
FORCEPROP 2 LAST $XR0 235 
J 0
(12289 3250);
DISPLAY 0.638298 (12289 3250);
PAINT MONO (12289 3250);
FORCEPROP 2 LAST BOM_COST PROC_VRD_PVCCIO_CPU0
J 0
(12300 3300);
DISPLAY 2.340426 (12300 3300);
PAINT WHITE (12300 3300);
DISPLAY INVISIBLE (12300 3300);
FORCEPROP 2 LAST PATH I52
J 0
(12300 3300);
DISPLAY 1.021277 (12300 3300);
PAINT ORANGE (12300 3300);
DISPLAY INVISIBLE (12300 3300);
FORCEPROP 2 LAST CDS_LIB mstr_standard
J 0
(12100 3250);
DISPLAY 1.617021 (12100 3250);
PAINT ORANGE (12100 3250);
DISPLAY INVISIBLE (12100 3250);
FORCEPROP 2 LAST ROOM PVCCIO_CPU0
J 0
(11700 3325);
DISPLAY 3.127660 (11700 3325);
PAINT WHITE (11700 3325);
DISPLAY INVISIBLE (11700 3325);
FORCEPROP 1 LAST OFFPAGE TRUE
J 0
(12425 3125);
PAINT GREEN (12425 3125);
DISPLAY INVISIBLE (12425 3125);
FORCEPROP 1 LAST COMMENT_BODY TRUE
J 0
(12055 3155);
DISPLAY 2.787234 (12055 3155);
PAINT PEACH (12055 3155);
DISPLAY INVISIBLE (12055 3155);
FORCEADD OFFPAGE..2
(11450 3075);
FORCEPROP 2 LAST $XR0 235 
J 0
(11639 3075);
DISPLAY 0.638298 (11639 3075);
PAINT MONO (11639 3075);
FORCEPROP 2 LAST ROOM PVCCIO_CPU0
J 0
(11050 3150);
DISPLAY 3.127660 (11050 3150);
PAINT WHITE (11050 3150);
DISPLAY INVISIBLE (11050 3150);
FORCEPROP 2 LAST CDS_LIB mstr_standard
J 0
(11450 3075);
DISPLAY 1.617021 (11450 3075);
PAINT ORANGE (11450 3075);
DISPLAY INVISIBLE (11450 3075);
FORCEPROP 2 LAST BOM_COST PROC_VRD_PVCCIO_CPU0
J 0
(11650 3125);
DISPLAY 2.340426 (11650 3125);
PAINT WHITE (11650 3125);
DISPLAY INVISIBLE (11650 3125);
FORCEPROP 2 LAST PATH I53
J 0
(11650 3125);
DISPLAY 1.021277 (11650 3125);
PAINT ORANGE (11650 3125);
DISPLAY INVISIBLE (11650 3125);
FORCEPROP 1 LAST OFFPAGE TRUE
J 0
(11775 2950);
PAINT GREEN (11775 2950);
DISPLAY INVISIBLE (11775 2950);
FORCEPROP 1 LAST COMMENT_BODY TRUE
J 0
(11405 2980);
DISPLAY 2.787234 (11405 2980);
PAINT PEACH (11405 2980);
DISPLAY INVISIBLE (11405 2980);
FORCEADD OFFPAGE..2
(11375 2725);
FORCEPROP 2 LAST $XR0 235 
J 0
(11564 2725);
DISPLAY 0.638298 (11564 2725);
PAINT MONO (11564 2725);
FORCEPROP 2 LAST PATH I54
J 0
(11575 2775);
DISPLAY 1.021277 (11575 2775);
PAINT ORANGE (11575 2775);
DISPLAY INVISIBLE (11575 2775);
FORCEPROP 2 LAST BOM_COST PROC_VRD_PVCCIO_CPU0
J 0
(11575 2775);
DISPLAY 2.340426 (11575 2775);
PAINT WHITE (11575 2775);
DISPLAY INVISIBLE (11575 2775);
FORCEPROP 2 LAST ROOM PVCCIO_CPU0
J 0
(10975 2800);
DISPLAY 3.127660 (10975 2800);
PAINT WHITE (10975 2800);
DISPLAY INVISIBLE (10975 2800);
FORCEPROP 2 LAST CDS_LIB mstr_standard
J 0
(11375 2725);
DISPLAY 1.617021 (11375 2725);
PAINT ORANGE (11375 2725);
DISPLAY INVISIBLE (11375 2725);
FORCEPROP 1 LAST OFFPAGE TRUE
J 0
(11700 2600);
PAINT GREEN (11700 2600);
DISPLAY INVISIBLE (11700 2600);
FORCEPROP 1 LAST COMMENT_BODY TRUE
J 0
(11330 2630);
DISPLAY 2.787234 (11330 2630);
PAINT PEACH (11330 2630);
DISPLAY INVISIBLE (11330 2630);
FORCEADD P1V05_PCH_STBY..1
(7675 1500);
FORCEPROP 3 LASTPIN (7675 1450) SIG_NAME P1V05_PCH_STBY\g
J 0
(7685 1460);
DISPLAY 0.659574 (7685 1460);
PAINT MONO (7685 1460);
DISPLAY INVISIBLE (7685 1460);
FORCEPROP 1 LAST PATH I55
J 0
(7725 1525);
DISPLAY 0.872340 (7725 1525);
PAINT AQUA (7725 1525);
DISPLAY INVISIBLE (7725 1525);
FORCEPROP 2 LAST ROOM PVCCIO_CPU0
J 0
(7675 1600);
DISPLAY 3.127660 (7675 1600);
PAINT WHITE (7675 1600);
DISPLAY INVISIBLE (7675 1600);
FORCEPROP 2 LAST BOM_COST PROC_VRD_PVCCIO_CPU0
J 0
(7675 1600);
DISPLAY 2.340426 (7675 1600);
PAINT WHITE (7675 1600);
DISPLAY INVISIBLE (7675 1600);
FORCEPROP 2 LAST CDS_LIB mstr_symbols
J 0
(7675 1500);
PAINT ORANGE (7675 1500);
DISPLAY INVISIBLE (7675 1500);
FORCEPROP 1 LAST VOLTAGE 1.05V
J 0
(7630 1457);
DISPLAY 0.340426 (7630 1457);
PAINT SKYBLUE (7630 1457);
DISPLAY INVISIBLE (7630 1457);
FORCEPROP 1 LAST BODY_TYPE PLUMBING
J 0
(7630 1457);
DISPLAY 0.340426 (7630 1457);
PAINT GREEN (7630 1457);
DISPLAY INVISIBLE (7630 1457);
FORCEPROP 1 LAST HDL_POWER P1V05_PCH_STBY
J 0
(7675 1550);
DISPLAY 0.872340 (7675 1550);
PAINT GREEN (7675 1550);
DISPLAY INVISIBLE (7675 1550);
FORCEADD RES..1
(7450 1300);
FORCEPROP 1 LAST LOCATION R8B14
J 0
(7250 1475);
DISPLAY 0.617021 (7250 1475);
PAINT AQUA (7250 1475);
FORCEPROP 1 LAST VALUE 0.0
J 2
(7325 1350);
DISPLAY 0.617021 (7325 1350);
PAINT SKYBLUE (7325 1350);
FORCEPROP 1 LASTPIN (7350 1300) $PN 1
J 0
(7362 1312);
DISPLAY 0.617021 (7362 1312);
PAINT ORANGE (7362 1312);
FORCEPROP 1 LAST WATTAGE 1/16W
J 2
(7525 1225);
DISPLAY 0.617021 (7525 1225);
PAINT SKYBLUE (7525 1225);
FORCEPROP 1 LASTPIN (7550 1300) $PN 2
J 0
(7512 1312);
DISPLAY 0.617021 (7512 1312);
PAINT ORANGE (7512 1312);
FORCEPROP 1 LAST TOLERANCE 5%
J 0
(7400 1350);
DISPLAY 0.617021 (7400 1350);
PAINT SKYBLUE (7400 1350);
FORCEPROP 1 LAST PART_NUMBER G21497-005
J 0
(7275 1425);
DISPLAY 0.617021 (7275 1425);
PAINT BLUE (7275 1425);
FORCEPROP 1 LAST MATERIAL CHIP
J 0
(7475 1375);
DISPLAY 0.638298 (7475 1375);
PAINT SKYBLUE (7475 1375);
FORCEPROP 1 LAST PACK_TYPE 0402
J 0
(7550 1250);
DISPLAY 0.617021 (7550 1250);
PAINT SKYBLUE (7550 1250);
FORCEPROP 2 LAST BOM_COST P1V05_PCH_STBY
J 0
(7525 1450);
PAINT MONO (7525 1450);
DISPLAY INVISIBLE (7525 1450);
FORCEPROP 2 LAST ROOM P1V05_PCH_STBY
J 0
(7400 1400);
PAINT ORANGE (7400 1400);
DISPLAY INVISIBLE (7400 1400);
FORCEPROP 1 LAST PATH I56
J 0
(7400 1450);
DISPLAY 0.978723 (7400 1450);
PAINT WHITE (7400 1450);
DISPLAY INVISIBLE (7400 1450);
FORCEPROP 2 LAST CDS_LIB mstr_discrete
J 0
(7450 1300);
PAINT ORANGE (7450 1300);
DISPLAY INVISIBLE (7450 1300);
FORCEPROP 2 LAST SEC 1
J 0
(7250 1525);
DISPLAY 0.680851 (7250 1525);
PAINT MONO (7250 1525);
DISPLAY INVISIBLE (7250 1525);
FORCEPROP 2 LAST SEC_TYPE 0402
J 0
(7250 1525);
DISPLAY 1.021277 (7250 1525);
PAINT ORANGE (7250 1525);
DISPLAY INVISIBLE (7250 1525);
FORCEPROP 2 LAST CDS_LOCATION R8B14
J 0
(7250 1475);
DISPLAY 0.617021 (7250 1475);
PAINT AQUA (7250 1475);
DISPLAY INVISIBLE (7250 1475);
FORCEADD RES..2
(7175 1050);
FORCEPROP 1 LASTPIN (7175 950) $PN 2
J 0
(7180 960);
DISPLAY 0.617021 (7180 960);
PAINT ORANGE (7180 960);
FORCEPROP 1 LAST PACK_TYPE 0402
J 0
(7215 875);
DISPLAY 0.617021 (7215 875);
PAINT SKYBLUE (7215 875);
FORCEPROP 1 LASTPIN (7175 1150) $PN 1
J 0
(7180 1112);
DISPLAY 0.617021 (7180 1112);
PAINT ORANGE (7180 1112);
FORCEPROP 1 LAST LOCATION R8B15
J 0
(7220 1175);
DISPLAY 0.617021 (7220 1175);
PAINT AQUA (7220 1175);
FORCEPROP 1 LAST VALUE 100.0
J 0
(7220 1125);
DISPLAY 0.617021 (7220 1125);
PAINT SKYBLUE (7220 1125);
FORCEPROP 1 LAST MATERIAL EMPTY
J 0
(7215 975);
DISPLAY 0.617021 (7215 975);
PAINT RED (7215 975);
FORCEPROP 1 LAST TOLERANCE 1%
J 0
(7220 1075);
DISPLAY 0.617021 (7220 1075);
PAINT SKYBLUE (7220 1075);
FORCEPROP 1 LAST WATTAGE 1/16W
J 0
(7215 1025);
DISPLAY 0.617021 (7215 1025);
PAINT SKYBLUE (7215 1025);
FORCEPROP 1 LAST PART_NUMBER G21796-017
J 0
(7215 925);
DISPLAY 0.617021 (7215 925);
PAINT BLUE (7215 925);
FORCEPROP 2 LAST CDS_LIB mstr_discrete
J 0
(7175 1050);
PAINT ORANGE (7175 1050);
DISPLAY INVISIBLE (7175 1050);
FORCEPROP 2 LAST CDS_LOCATION R8B15
J 0
(7220 1175);
DISPLAY 0.617021 (7220 1175);
PAINT AQUA (7220 1175);
DISPLAY INVISIBLE (7220 1175);
FORCEPROP 1 LAST PATH I57
J 0
(7225 1225);
DISPLAY 0.978723 (7225 1225);
PAINT WHITE (7225 1225);
DISPLAY INVISIBLE (7225 1225);
FORCEPROP 2 LAST SEC_TYPE 0402
J 0
(7225 1275);
DISPLAY 1.021277 (7225 1275);
PAINT ORANGE (7225 1275);
DISPLAY INVISIBLE (7225 1275);
FORCEPROP 2 LAST SEC 1
J 0
(7225 1275);
DISPLAY 0.680851 (7225 1275);
PAINT MONO (7225 1275);
DISPLAY INVISIBLE (7225 1275);
FORCEPROP 2 LAST NO_XNET_CONNECTION 1
J 0
(7225 1275);
PAINT MONO (7225 1275);
DISPLAY INVISIBLE (7225 1275);
FORCEPROP 0 LAST ROOM P1V05_PCH_STBY
J 0
(7225 1275);
DISPLAY 1.021277 (7225 1275);
PAINT ORANGE (7225 1275);
DISPLAY INVISIBLE (7225 1275);
FORCEPROP 0 LAST BOM_COST P1V05_PCH_STBY
J 0
(7225 1375);
DISPLAY 1.021277 (7225 1375);
PAINT ORANGE (7225 1375);
DISPLAY INVISIBLE (7225 1375);
FORCEADD GND..1
(7650 625);
FORCEPROP 3 LASTPIN (7650 675) SIG_NAME GND\g
J 0
(7660 685);
DISPLAY 0.659574 (7660 685);
PAINT MONO (7660 685);
DISPLAY INVISIBLE (7660 685);
FORCEPROP 1 LAST PATH I58
J 0
(7725 625);
DISPLAY 0.872340 (7725 625);
PAINT AQUA (7725 625);
DISPLAY INVISIBLE (7725 625);
FORCEPROP 1 LAST SIZE 1B
J 0
(7725 575);
DISPLAY 0.893617 (7725 575);
PAINT GREEN (7725 575);
DISPLAY INVISIBLE (7725 575);
FORCEPROP 1 LAST VOLTAGE 0
J 0
(7650 625);
PAINT SKYBLUE (7650 625);
DISPLAY INVISIBLE (7650 625);
FORCEPROP 2 LAST CDS_LIB mstr_symbols
J 0
(7650 625);
PAINT ORANGE (7650 625);
DISPLAY INVISIBLE (7650 625);
FORCEPROP 2 LAST BOM_COST MEM_VRD_PVPP_AB
J 0
(7325 700);
PAINT MONO (7325 700);
DISPLAY INVISIBLE (7325 700);
FORCEPROP 2 LAST ROOM VCCP_CPU0_VR
J 0
(7100 700);
PAINT ORANGE (7100 700);
DISPLAY INVISIBLE (7100 700);
FORCEPROP 1 LAST BODY_TYPE PLUMBING
J 0
(7605 582);
DISPLAY 0.340426 (7605 582);
PAINT GREEN (7605 582);
DISPLAY INVISIBLE (7605 582);
FORCEPROP 1 LAST HDL_POWER GND
J 0
(7650 775);
DISPLAY 0.893617 (7650 775);
PAINT GREEN (7650 775);
DISPLAY INVISIBLE (7650 775);
FORCEADD RES..1
(7425 850);
FORCEPROP 1 LAST WATTAGE 1/16W
J 2
(7400 700);
DISPLAY 0.617021 (7400 700);
PAINT SKYBLUE (7400 700);
FORCEPROP 1 LAST PACK_TYPE 0402
J 0
(7300 650);
DISPLAY 0.617021 (7300 650);
PAINT SKYBLUE (7300 650);
FORCEPROP 1 LASTPIN (7325 850) $PN 1
J 0
(7337 862);
DISPLAY 0.617021 (7337 862);
PAINT ORANGE (7337 862);
FORCEPROP 1 LAST VALUE 0.0
J 2
(7400 775);
DISPLAY 0.617021 (7400 775);
PAINT SKYBLUE (7400 775);
FORCEPROP 1 LASTPIN (7525 850) $PN 2
J 0
(7487 862);
DISPLAY 0.617021 (7487 862);
PAINT ORANGE (7487 862);
FORCEPROP 1 LAST TOLERANCE 5%
J 0
(7425 775);
DISPLAY 0.617021 (7425 775);
PAINT SKYBLUE (7425 775);
FORCEPROP 1 LAST LOCATION R8B12
J 0
(7500 900);
DISPLAY 0.617021 (7500 900);
PAINT AQUA (7500 900);
FORCEPROP 1 LAST MATERIAL CHIP
J 0
(7425 700);
DISPLAY 0.638298 (7425 700);
PAINT SKYBLUE (7425 700);
FORCEPROP 1 LAST PART_NUMBER G21497-005
J 0
(7500 950);
DISPLAY 0.617021 (7500 950);
PAINT BLUE (7500 950);
FORCEPROP 2 LAST SEC_TYPE 0402
J 0
(7375 1050);
DISPLAY 1.021277 (7375 1050);
PAINT ORANGE (7375 1050);
DISPLAY INVISIBLE (7375 1050);
FORCEPROP 2 LAST SEC 1
J 0
(7375 1050);
DISPLAY 0.680851 (7375 1050);
PAINT MONO (7375 1050);
DISPLAY INVISIBLE (7375 1050);
FORCEPROP 1 LAST PATH I59
J 0
(7375 1000);
DISPLAY 0.978723 (7375 1000);
PAINT WHITE (7375 1000);
DISPLAY INVISIBLE (7375 1000);
FORCEPROP 2 LAST BOM_COST P1V05_PCH_STBY
J 0
(7500 1000);
PAINT MONO (7500 1000);
DISPLAY INVISIBLE (7500 1000);
FORCEPROP 2 LAST CDS_LIB mstr_discrete
J 0
(7425 850);
PAINT ORANGE (7425 850);
DISPLAY INVISIBLE (7425 850);
FORCEPROP 2 LAST CDS_LOCATION R8B12
J 0
(7500 900);
DISPLAY 0.617021 (7500 900);
PAINT AQUA (7500 900);
DISPLAY INVISIBLE (7500 900);
FORCEPROP 2 LAST ROOM P1V05_PCH_STBY
J 0
(7375 950);
PAINT ORANGE (7375 950);
DISPLAY INVISIBLE (7375 950);
FORCEADD OFFPAGE..1
(6250 1275);
FORCEPROP 2 LAST $XR0 235 
J 0
(5968 1275);
DISPLAY 0.638298 (5968 1275);
PAINT MONO (5968 1275);
FORCEPROP 2 LAST CDS_LIB mstr_standard
J 0
(6250 1275);
PAINT ORANGE (6250 1275);
DISPLAY INVISIBLE (6250 1275);
FORCEPROP 2 LAST PATH I60
J 0
(6300 1350);
DISPLAY 1.021277 (6300 1350);
PAINT ORANGE (6300 1350);
DISPLAY INVISIBLE (6300 1350);
FORCEPROP 1 LAST OFFPAGE TRUE
J 0
(6575 1150);
DISPLAY 1.170213 (6575 1150);
PAINT GREEN (6575 1150);
DISPLAY INVISIBLE (6575 1150);
FORCEPROP 1 LAST COMMENT_BODY TRUE
J 0
(6375 1175);
DISPLAY 1.170213 (6375 1175);
PAINT GREEN (6375 1175);
DISPLAY INVISIBLE (6375 1175);
FORCEADD OFFPAGE..1
(6225 950);
FORCEPROP 2 LAST $XR0 235 
J 0
(5943 950);
DISPLAY 0.638298 (5943 950);
PAINT MONO (5943 950);
FORCEPROP 2 LAST PATH I61
J 0
(6275 1025);
DISPLAY 1.021277 (6275 1025);
PAINT ORANGE (6275 1025);
DISPLAY INVISIBLE (6275 1025);
FORCEPROP 2 LAST CDS_LIB mstr_standard
J 0
(6225 950);
PAINT ORANGE (6225 950);
DISPLAY INVISIBLE (6225 950);
FORCEPROP 2 LAST BOM_COST MEM_VRD_PVPP_AB
J 0
(5950 1000);
PAINT MONO (5950 1000);
DISPLAY INVISIBLE (5950 1000);
FORCEPROP 1 LAST OFFPAGE TRUE
J 0
(6550 825);
DISPLAY 0.893617 (6550 825);
PAINT GREEN (6550 825);
DISPLAY INVISIBLE (6550 825);
FORCEPROP 1 LAST COMMENT_BODY TRUE
J 0
(6350 850);
DISPLAY 0.893617 (6350 850);
PAINT GREEN (6350 850);
DISPLAY INVISIBLE (6350 850);
FORCEADD PVNN_PCH_STBY..1
(12650 4075);
FORCEPROP 3 LASTPIN (12650 4025) SIG_NAME PVNN_PCH_STBY\g
J 0
(12660 4035);
DISPLAY 0.659574 (12660 4035);
PAINT MONO (12660 4035);
DISPLAY INVISIBLE (12660 4035);
FORCEPROP 1 LAST HDL_POWER PVNN_PCH_STBY
J 1
(12650 4125);
DISPLAY 0.872340 (12650 4125);
PAINT GREEN (12650 4125);
DISPLAY INVISIBLE (12650 4125);
FORCEPROP 1 LAST BODY_TYPE PLUMBING
J 0
(12605 4032);
DISPLAY 0.340426 (12605 4032);
PAINT GREEN (12605 4032);
DISPLAY INVISIBLE (12605 4032);
FORCEPROP 1 LAST VOLTAGE 1.0V
J 0
(12605 4032);
DISPLAY 0.340426 (12605 4032);
PAINT SKYBLUE (12605 4032);
DISPLAY INVISIBLE (12605 4032);
FORCEPROP 2 LAST CDS_LIB mstr_symbols
J 0
(12650 4075);
PAINT ORANGE (12650 4075);
DISPLAY INVISIBLE (12650 4075);
FORCEPROP 2 LAST BOM_COST PROC_VRD_PVCCIO_CPU0
J 0
(12650 4175);
DISPLAY 2.340426 (12650 4175);
PAINT WHITE (12650 4175);
DISPLAY INVISIBLE (12650 4175);
FORCEPROP 1 LAST PATH I7
J 0
(12700 4100);
DISPLAY 0.872340 (12700 4100);
PAINT AQUA (12700 4100);
DISPLAY INVISIBLE (12700 4100);
FORCEPROP 2 LAST ROOM PVCCIO_CPU0
J 0
(12650 4175);
DISPLAY 3.127660 (12650 4175);
PAINT WHITE (12650 4175);
DISPLAY INVISIBLE (12650 4175);
FORCEADD CAPP..1
(12025 3775);
FORCEPROP 1 LASTPIN (12025 3875) $PN 1
J 0
(12035 3860);
DISPLAY 0.617021 (12035 3860);
PAINT ORANGE (12035 3860);
FORCEPROP 1 LAST VOLTAGE 2V
J 0
(12075 3725);
DISPLAY 0.617021 (12075 3725);
PAINT SKYBLUE (12075 3725);
FORCEPROP 1 LAST TOLERANCE 20%
J 0
(12075 3775);
DISPLAY 0.617021 (12075 3775);
PAINT SKYBLUE (12075 3775);
FORCEPROP 1 LASTPIN (12025 3675) $PN 2
J 0
(12035 3660);
DISPLAY 0.617021 (12035 3660);
PAINT ORANGE (12035 3660);
FORCEPROP 1 LAST PACK_TYPE SM
J 0
(12075 3625);
DISPLAY 0.617021 (12075 3625);
PAINT SKYBLUE (12075 3625);
FORCEPROP 1 LAST VALUE 470UF
J 0
(12075 3825);
DISPLAY 0.617021 (12075 3825);
PAINT SKYBLUE (12075 3825);
FORCEPROP 1 LAST LOCATION C3L18
J 0
(12075 3875);
DISPLAY 0.617021 (12075 3875);
PAINT AQUA (12075 3875);
FORCEPROP 1 LAST MATERIAL ALUM
J 0
(12075 3675);
DISPLAY 0.617021 (12075 3675);
PAINT SKYBLUE (12075 3675);
FORCEPROP 1 LAST PART_NUMBER 699013-031
J 0
(12075 3575);
DISPLAY 0.617021 (12075 3575);
PAINT BLUE (12075 3575);
FORCEPROP 2 LAST CDS_LIB mstr_discrete
J 0
(12025 3775);
PAINT ORANGE (12025 3775);
DISPLAY INVISIBLE (12025 3775);
FORCEPROP 2 LAST SEC_TYPE SM
J 0
(12075 3975);
DISPLAY 1.021277 (12075 3975);
PAINT ORANGE (12075 3975);
DISPLAY INVISIBLE (12075 3975);
FORCEPROP 2 LAST SEC 1
J 0
(12075 3975);
DISPLAY 0.680851 (12075 3975);
PAINT MONO (12075 3975);
DISPLAY INVISIBLE (12075 3975);
FORCEPROP 2 LAST CDS_LOCATION C3L18
J 0
(12075 3875);
DISPLAY 0.617021 (12075 3875);
PAINT AQUA (12075 3875);
DISPLAY INVISIBLE (12075 3875);
FORCEPROP 1 LAST PATH I71
J 0
(12075 3925);
DISPLAY 0.978723 (12075 3925);
PAINT ORANGE (12075 3925);
DISPLAY INVISIBLE (12075 3925);
FORCEPROP 0 LAST ROOM PVNN_PCH_STBY
J 0
(12075 3975);
DISPLAY 1.021277 (12075 3975);
PAINT ORANGE (12075 3975);
DISPLAY INVISIBLE (12075 3975);
FORCEADD CAPP..1
(12325 3775);
FORCEPROP 1 LAST VOLTAGE 2V
J 0
(12375 3725);
DISPLAY 0.617021 (12375 3725);
PAINT SKYBLUE (12375 3725);
FORCEPROP 1 LAST TOLERANCE 20%
J 0
(12375 3775);
DISPLAY 0.617021 (12375 3775);
PAINT SKYBLUE (12375 3775);
FORCEPROP 1 LASTPIN (12325 3675) $PN 2
J 0
(12335 3660);
DISPLAY 0.617021 (12335 3660);
PAINT ORANGE (12335 3660);
FORCEPROP 1 LASTPIN (12325 3875) $PN 1
J 0
(12335 3860);
DISPLAY 0.617021 (12335 3860);
PAINT ORANGE (12335 3860);
FORCEPROP 1 LAST VALUE 470UF
J 0
(12375 3825);
DISPLAY 0.617021 (12375 3825);
PAINT SKYBLUE (12375 3825);
FORCEPROP 1 LAST PACK_TYPE SM
J 0
(12375 3625);
DISPLAY 0.617021 (12375 3625);
PAINT SKYBLUE (12375 3625);
FORCEPROP 1 LAST LOCATION C3L20
J 0
(12375 3875);
DISPLAY 0.617021 (12375 3875);
PAINT AQUA (12375 3875);
FORCEPROP 1 LAST MATERIAL ALUM
J 0
(12375 3675);
DISPLAY 0.617021 (12375 3675);
PAINT SKYBLUE (12375 3675);
FORCEPROP 1 LAST PART_NUMBER 699013-031
J 0
(12375 3575);
DISPLAY 0.617021 (12375 3575);
PAINT BLUE (12375 3575);
FORCEPROP 2 LAST CDS_LIB mstr_discrete
J 0
(12325 3775);
PAINT ORANGE (12325 3775);
DISPLAY INVISIBLE (12325 3775);
FORCEPROP 2 LAST SEC_TYPE SM
J 0
(12375 3975);
DISPLAY 1.021277 (12375 3975);
PAINT ORANGE (12375 3975);
DISPLAY INVISIBLE (12375 3975);
FORCEPROP 2 LAST SEC 1
J 0
(12375 3975);
DISPLAY 0.680851 (12375 3975);
PAINT MONO (12375 3975);
DISPLAY INVISIBLE (12375 3975);
FORCEPROP 2 LAST CDS_LOCATION C3L20
J 0
(12375 3875);
DISPLAY 0.617021 (12375 3875);
PAINT AQUA (12375 3875);
DISPLAY INVISIBLE (12375 3875);
FORCEPROP 1 LAST PATH I73
J 0
(12375 3925);
DISPLAY 0.978723 (12375 3925);
PAINT ORANGE (12375 3925);
DISPLAY INVISIBLE (12375 3925);
FORCEPROP 0 LAST ROOM PVNN_PCH_STBY
J 0
(12375 3975);
DISPLAY 1.021277 (12375 3975);
PAINT ORANGE (12375 3975);
DISPLAY INVISIBLE (12375 3975);
FORCEADD CAPP..1
(12600 3775);
FORCEPROP 1 LASTPIN (12600 3675) $PN 2
J 0
(12610 3660);
DISPLAY 0.617021 (12610 3660);
PAINT ORANGE (12610 3660);
FORCEPROP 1 LASTPIN (12600 3875) $PN 1
J 0
(12610 3860);
DISPLAY 0.617021 (12610 3860);
PAINT ORANGE (12610 3860);
FORCEPROP 1 LAST LOCATION C3L21
J 0
(12650 3875);
DISPLAY 0.617021 (12650 3875);
PAINT AQUA (12650 3875);
FORCEPROP 1 LAST VALUE 470UF
J 0
(12650 3825);
DISPLAY 0.617021 (12650 3825);
PAINT SKYBLUE (12650 3825);
FORCEPROP 1 LAST TOLERANCE 20%
J 0
(12650 3775);
DISPLAY 0.617021 (12650 3775);
PAINT SKYBLUE (12650 3775);
FORCEPROP 1 LAST VOLTAGE 2V
J 0
(12650 3725);
DISPLAY 0.617021 (12650 3725);
PAINT SKYBLUE (12650 3725);
FORCEPROP 1 LAST MATERIAL ALUM
J 0
(12650 3675);
DISPLAY 0.617021 (12650 3675);
PAINT SKYBLUE (12650 3675);
FORCEPROP 1 LAST PACK_TYPE SM
J 0
(12650 3625);
DISPLAY 0.617021 (12650 3625);
PAINT SKYBLUE (12650 3625);
FORCEPROP 1 LAST PART_NUMBER 699013-031
J 0
(12650 3575);
DISPLAY 0.617021 (12650 3575);
PAINT BLUE (12650 3575);
FORCEPROP 2 LAST CDS_LIB mstr_discrete
J 0
(12600 3775);
PAINT ORANGE (12600 3775);
DISPLAY INVISIBLE (12600 3775);
FORCEPROP 2 LAST SEC_TYPE SM
J 0
(12650 3975);
DISPLAY 1.021277 (12650 3975);
PAINT ORANGE (12650 3975);
DISPLAY INVISIBLE (12650 3975);
FORCEPROP 2 LAST SEC 1
J 0
(12650 3975);
DISPLAY 0.680851 (12650 3975);
PAINT MONO (12650 3975);
DISPLAY INVISIBLE (12650 3975);
FORCEPROP 2 LAST CDS_LOCATION C3L21
J 0
(12650 3875);
DISPLAY 0.617021 (12650 3875);
PAINT AQUA (12650 3875);
DISPLAY INVISIBLE (12650 3875);
FORCEPROP 1 LAST PATH I74
J 0
(12650 3925);
DISPLAY 0.978723 (12650 3925);
PAINT ORANGE (12650 3925);
DISPLAY INVISIBLE (12650 3925);
FORCEPROP 0 LAST ROOM PVNN_PCH_STBY
J 0
(12650 3975);
DISPLAY 1.021277 (12650 3975);
PAINT ORANGE (12650 3975);
DISPLAY INVISIBLE (12650 3975);
FORCEADD CAPP..1
(12850 3775);
FORCEPROP 1 LAST LOCATION C7A27
J 0
(12900 3875);
DISPLAY 0.617021 (12900 3875);
PAINT AQUA (12900 3875);
FORCEPROP 1 LAST VALUE 470UF
J 0
(12900 3825);
DISPLAY 0.617021 (12900 3825);
PAINT SKYBLUE (12900 3825);
FORCEPROP 1 LAST VOLTAGE 2V
J 0
(12900 3725);
DISPLAY 0.617021 (12900 3725);
PAINT SKYBLUE (12900 3725);
FORCEPROP 1 LAST MATERIAL ALUM
J 0
(12900 3675);
DISPLAY 0.617021 (12900 3675);
PAINT SKYBLUE (12900 3675);
FORCEPROP 1 LAST PACK_TYPE SM
J 0
(12900 3625);
DISPLAY 0.617021 (12900 3625);
PAINT SKYBLUE (12900 3625);
FORCEPROP 1 LASTPIN (12850 3675) $PN 2
J 0
(12860 3660);
DISPLAY 0.617021 (12860 3660);
PAINT ORANGE (12860 3660);
FORCEPROP 1 LASTPIN (12850 3875) $PN 1
J 0
(12860 3860);
DISPLAY 0.617021 (12860 3860);
PAINT ORANGE (12860 3860);
FORCEPROP 1 LAST TOLERANCE 20%
J 0
(12900 3775);
DISPLAY 0.617021 (12900 3775);
PAINT SKYBLUE (12900 3775);
FORCEPROP 1 LAST PART_NUMBER 699013-031
J 0
(12900 3575);
DISPLAY 0.617021 (12900 3575);
PAINT BLUE (12900 3575);
FORCEPROP 2 LAST CDS_LIB mstr_discrete
J 0
(12850 3775);
PAINT ORANGE (12850 3775);
DISPLAY INVISIBLE (12850 3775);
FORCEPROP 2 LAST CDS_LOCATION C7A27
J 0
(12900 3875);
DISPLAY 0.617021 (12900 3875);
PAINT AQUA (12900 3875);
DISPLAY INVISIBLE (12900 3875);
FORCEPROP 1 LAST PATH I75
J 0
(12900 3925);
DISPLAY 0.978723 (12900 3925);
PAINT ORANGE (12900 3925);
DISPLAY INVISIBLE (12900 3925);
FORCEPROP 2 LAST SEC_TYPE SM
J 0
(12900 3975);
DISPLAY 1.021277 (12900 3975);
PAINT ORANGE (12900 3975);
DISPLAY INVISIBLE (12900 3975);
FORCEPROP 2 LAST SEC 1
J 0
(12900 3975);
DISPLAY 0.680851 (12900 3975);
PAINT MONO (12900 3975);
DISPLAY INVISIBLE (12900 3975);
FORCEPROP 0 LAST ROOM PVNN_PCH_STBY
J 0
(12900 3975);
DISPLAY 1.021277 (12900 3975);
PAINT ORANGE (12900 3975);
DISPLAY INVISIBLE (12900 3975);
FORCEADD CAPP..1
(11925 2050);
FORCEPROP 1 LAST VOLTAGE 2V
J 0
(11975 2000);
DISPLAY 0.617021 (11975 2000);
PAINT SKYBLUE (11975 2000);
FORCEPROP 1 LAST LOCATION C3L19
J 0
(11975 2150);
DISPLAY 0.617021 (11975 2150);
PAINT AQUA (11975 2150);
FORCEPROP 1 LAST VALUE 470UF
J 0
(11975 2100);
DISPLAY 0.617021 (11975 2100);
PAINT SKYBLUE (11975 2100);
FORCEPROP 1 LASTPIN (11925 2150) $PN 1
J 0
(11935 2135);
DISPLAY 0.617021 (11935 2135);
PAINT ORANGE (11935 2135);
FORCEPROP 1 LAST TOLERANCE 20%
J 0
(11975 2050);
DISPLAY 0.617021 (11975 2050);
PAINT SKYBLUE (11975 2050);
FORCEPROP 1 LAST MATERIAL ALUM
J 0
(11975 1950);
DISPLAY 0.617021 (11975 1950);
PAINT SKYBLUE (11975 1950);
FORCEPROP 1 LAST PACK_TYPE SM
J 0
(11975 1900);
DISPLAY 0.617021 (11975 1900);
PAINT SKYBLUE (11975 1900);
FORCEPROP 1 LAST PART_NUMBER 699013-031
J 0
(11975 1850);
DISPLAY 0.617021 (11975 1850);
PAINT BLUE (11975 1850);
FORCEPROP 1 LASTPIN (11925 1950) $PN 2
J 0
(11935 1935);
DISPLAY 0.617021 (11935 1935);
PAINT ORANGE (11935 1935);
FORCEPROP 2 LAST CDS_LIB mstr_discrete
J 0
(11925 2050);
PAINT ORANGE (11925 2050);
DISPLAY INVISIBLE (11925 2050);
FORCEPROP 2 LAST CDS_LOCATION C3L19
J 0
(11975 2150);
DISPLAY 0.617021 (11975 2150);
PAINT AQUA (11975 2150);
DISPLAY INVISIBLE (11975 2150);
FORCEPROP 1 LAST PATH I76
J 0
(11975 2200);
DISPLAY 0.978723 (11975 2200);
PAINT ORANGE (11975 2200);
DISPLAY INVISIBLE (11975 2200);
FORCEPROP 0 LAST ROOM P1V05_PCH_STBY
J 0
(11975 2250);
DISPLAY 1.021277 (11975 2250);
PAINT ORANGE (11975 2250);
DISPLAY INVISIBLE (11975 2250);
FORCEPROP 2 LAST SEC_TYPE SM
J 0
(11975 2250);
DISPLAY 1.021277 (11975 2250);
PAINT ORANGE (11975 2250);
DISPLAY INVISIBLE (11975 2250);
FORCEPROP 2 LAST SEC 1
J 0
(11975 2250);
DISPLAY 0.680851 (11975 2250);
PAINT MONO (11975 2250);
DISPLAY INVISIBLE (11975 2250);
FORCEADD CAPP..1
(12175 2050);
FORCEPROP 1 LAST TOLERANCE 20%
J 0
(12225 2050);
DISPLAY 0.617021 (12225 2050);
PAINT SKYBLUE (12225 2050);
FORCEPROP 1 LASTPIN (12175 2150) $PN 1
J 0
(12185 2135);
DISPLAY 0.787234 (12185 2135);
PAINT ORANGE (12185 2135);
FORCEPROP 1 LAST VALUE 470UF
J 0
(12225 2100);
DISPLAY 0.617021 (12225 2100);
PAINT SKYBLUE (12225 2100);
FORCEPROP 1 LAST LOCATION C2L46
J 0
(12225 2150);
DISPLAY 0.617021 (12225 2150);
PAINT AQUA (12225 2150);
FORCEPROP 1 LAST PART_NUMBER 699013-031
J 0
(12225 1850);
DISPLAY 0.617021 (12225 1850);
PAINT BLUE (12225 1850);
FORCEPROP 1 LAST VOLTAGE 2V
J 0
(12225 2000);
DISPLAY 0.617021 (12225 2000);
PAINT SKYBLUE (12225 2000);
FORCEPROP 1 LAST PACK_TYPE SM
J 0
(12225 1900);
DISPLAY 0.617021 (12225 1900);
PAINT SKYBLUE (12225 1900);
FORCEPROP 1 LAST MATERIAL ALUM
J 0
(12225 1950);
DISPLAY 0.617021 (12225 1950);
PAINT SKYBLUE (12225 1950);
FORCEPROP 1 LASTPIN (12175 1950) $PN 2
J 0
(12185 1935);
DISPLAY 0.787234 (12185 1935);
PAINT ORANGE (12185 1935);
FORCEPROP 0 LAST ROOM P1V05_PCH_STBY
J 0
(12225 2250);
DISPLAY 1.021277 (12225 2250);
PAINT ORANGE (12225 2250);
DISPLAY INVISIBLE (12225 2250);
FORCEPROP 1 LAST PATH I77
J 0
(12225 2200);
DISPLAY 0.978723 (12225 2200);
PAINT ORANGE (12225 2200);
DISPLAY INVISIBLE (12225 2200);
FORCEPROP 2 LAST CDS_LOCATION C2L46
J 0
(12225 2150);
DISPLAY 0.617021 (12225 2150);
PAINT AQUA (12225 2150);
DISPLAY INVISIBLE (12225 2150);
FORCEPROP 2 LAST CDS_LIB mstr_discrete
J 0
(12175 2050);
PAINT ORANGE (12175 2050);
DISPLAY INVISIBLE (12175 2050);
FORCEPROP 2 LAST SEC 1
J 0
(12225 2250);
PAINT MONO (12225 2250);
DISPLAY INVISIBLE (12225 2250);
FORCEPROP 2 LAST SEC_TYPE SM
J 0
(12225 2250);
DISPLAY 1.021277 (12225 2250);
PAINT ORANGE (12225 2250);
DISPLAY INVISIBLE (12225 2250);
FORCEADD CAPP..1
(12425 2050);
FORCEPROP 1 LAST VOLTAGE 2V
J 0
(12475 2000);
DISPLAY 0.617021 (12475 2000);
PAINT SKYBLUE (12475 2000);
FORCEPROP 1 LAST PACK_TYPE SM
J 0
(12475 1900);
DISPLAY 0.617021 (12475 1900);
PAINT SKYBLUE (12475 1900);
FORCEPROP 1 LASTPIN (12425 2150) $PN 1
J 0
(12435 2135);
DISPLAY 0.787234 (12435 2135);
PAINT ORANGE (12435 2135);
FORCEPROP 1 LAST VALUE 470UF
J 0
(12475 2100);
DISPLAY 0.617021 (12475 2100);
PAINT SKYBLUE (12475 2100);
FORCEPROP 1 LAST TOLERANCE 20%
J 0
(12475 2050);
DISPLAY 0.617021 (12475 2050);
PAINT SKYBLUE (12475 2050);
FORCEPROP 1 LAST PART_NUMBER 699013-031
J 0
(12475 1850);
DISPLAY 0.617021 (12475 1850);
PAINT BLUE (12475 1850);
FORCEPROP 1 LAST LOCATION C8A15
J 0
(12475 2150);
DISPLAY 0.617021 (12475 2150);
PAINT AQUA (12475 2150);
FORCEPROP 1 LAST MATERIAL ALUM
J 0
(12475 1950);
DISPLAY 0.617021 (12475 1950);
PAINT SKYBLUE (12475 1950);
FORCEPROP 1 LASTPIN (12425 1950) $PN 2
J 0
(12435 1935);
DISPLAY 0.787234 (12435 1935);
PAINT ORANGE (12435 1935);
FORCEPROP 2 LAST CDS_LIB mstr_discrete
J 0
(12425 2050);
PAINT ORANGE (12425 2050);
DISPLAY INVISIBLE (12425 2050);
FORCEPROP 2 LAST CDS_LOCATION C8A15
J 0
(12475 2150);
DISPLAY 0.617021 (12475 2150);
PAINT AQUA (12475 2150);
DISPLAY INVISIBLE (12475 2150);
FORCEPROP 1 LAST PATH I78
J 0
(12475 2200);
DISPLAY 0.978723 (12475 2200);
PAINT ORANGE (12475 2200);
DISPLAY INVISIBLE (12475 2200);
FORCEPROP 0 LAST ROOM P1V05_PCH_STBY
J 0
(12475 2250);
DISPLAY 1.021277 (12475 2250);
PAINT ORANGE (12475 2250);
DISPLAY INVISIBLE (12475 2250);
FORCEPROP 2 LAST SEC 1
J 0
(12475 2250);
PAINT MONO (12475 2250);
DISPLAY INVISIBLE (12475 2250);
FORCEPROP 2 LAST SEC_TYPE SM
J 0
(12475 2250);
DISPLAY 1.021277 (12475 2250);
PAINT ORANGE (12475 2250);
DISPLAY INVISIBLE (12475 2250);
FORCEADD CAPP..1
(12700 2050);
FORCEPROP 1 LAST LOCATION C2L25
J 0
(12750 2150);
DISPLAY 0.617021 (12750 2150);
PAINT AQUA (12750 2150);
FORCEPROP 1 LASTPIN (12700 2150) $PN 1
J 0
(12710 2135);
DISPLAY 0.787234 (12710 2135);
PAINT ORANGE (12710 2135);
FORCEPROP 1 LAST VALUE 470UF
J 0
(12750 2100);
DISPLAY 0.617021 (12750 2100);
PAINT SKYBLUE (12750 2100);
FORCEPROP 1 LAST TOLERANCE 20%
J 0
(12750 2050);
DISPLAY 0.617021 (12750 2050);
PAINT SKYBLUE (12750 2050);
FORCEPROP 1 LAST PACK_TYPE SM
J 0
(12750 1900);
DISPLAY 0.617021 (12750 1900);
PAINT SKYBLUE (12750 1900);
FORCEPROP 1 LAST PART_NUMBER 699013-031
J 0
(12750 1850);
DISPLAY 0.617021 (12750 1850);
PAINT BLUE (12750 1850);
FORCEPROP 1 LAST VOLTAGE 2V
J 0
(12750 2000);
DISPLAY 0.617021 (12750 2000);
PAINT SKYBLUE (12750 2000);
FORCEPROP 1 LAST MATERIAL ALUM
J 0
(12750 1950);
DISPLAY 0.617021 (12750 1950);
PAINT SKYBLUE (12750 1950);
FORCEPROP 1 LASTPIN (12700 1950) $PN 2
J 0
(12710 1935);
DISPLAY 0.787234 (12710 1935);
PAINT ORANGE (12710 1935);
FORCEPROP 2 LAST CDS_LIB mstr_discrete
J 0
(12700 2050);
PAINT ORANGE (12700 2050);
DISPLAY INVISIBLE (12700 2050);
FORCEPROP 2 LAST CDS_LOCATION C2L25
J 0
(12750 2150);
DISPLAY 0.617021 (12750 2150);
PAINT AQUA (12750 2150);
DISPLAY INVISIBLE (12750 2150);
FORCEPROP 1 LAST PATH I79
J 0
(12750 2200);
DISPLAY 0.978723 (12750 2200);
PAINT ORANGE (12750 2200);
DISPLAY INVISIBLE (12750 2200);
FORCEPROP 0 LAST ROOM P1V05_PCH_STBY
J 0
(12750 2250);
DISPLAY 1.021277 (12750 2250);
PAINT ORANGE (12750 2250);
DISPLAY INVISIBLE (12750 2250);
FORCEPROP 2 LAST SEC 1
J 0
(12750 2250);
PAINT MONO (12750 2250);
DISPLAY INVISIBLE (12750 2250);
FORCEPROP 2 LAST SEC_TYPE SM
J 0
(12750 2250);
DISPLAY 1.021277 (12750 2250);
PAINT ORANGE (12750 2250);
DISPLAY INVISIBLE (12750 2250);
FORCEADD GND..1
(11725 3550);
FORCEPROP 3 LASTPIN (11725 3600) SIG_NAME GND\g
J 0
(11735 3610);
DISPLAY 0.659574 (11735 3610);
PAINT MONO (11735 3610);
DISPLAY INVISIBLE (11735 3610);
FORCEPROP 2 LAST BOM_COST PROC_VRD_PVCCIO_CPU0
J 0
(11350 3625);
DISPLAY 2.340426 (11350 3625);
PAINT WHITE (11350 3625);
DISPLAY INVISIBLE (11350 3625);
FORCEPROP 2 LAST ROOM PVCCIO_CPU0
J 0
(11175 3625);
DISPLAY 3.127660 (11175 3625);
PAINT WHITE (11175 3625);
DISPLAY INVISIBLE (11175 3625);
FORCEPROP 1 LAST VOLTAGE 0.0V
J 0
(11680 3507);
DISPLAY 0.340426 (11680 3507);
PAINT SKYBLUE (11680 3507);
DISPLAY INVISIBLE (11680 3507);
FORCEPROP 1 LAST PATH I8
J 0
(11800 3550);
DISPLAY 0.872340 (11800 3550);
PAINT AQUA (11800 3550);
DISPLAY INVISIBLE (11800 3550);
FORCEPROP 1 LAST SIZE 1B
J 0
(11800 3500);
DISPLAY 2.787234 (11800 3500);
PAINT GREEN (11800 3500);
DISPLAY INVISIBLE (11800 3500);
FORCEPROP 2 LAST CDS_LIB mstr_symbols
J 0
(11725 3550);
DISPLAY 1.617021 (11725 3550);
PAINT ORANGE (11725 3550);
DISPLAY INVISIBLE (11725 3550);
FORCEPROP 1 LAST BODY_TYPE PLUMBING
J 0
(11680 3507);
DISPLAY 0.340426 (11680 3507);
PAINT GREEN (11680 3507);
DISPLAY INVISIBLE (11680 3507);
FORCEPROP 1 LAST HDL_POWER GND
J 0
(11725 3700);
DISPLAY 2.787234 (11725 3700);
PAINT GREEN (11725 3700);
DISPLAY INVISIBLE (11725 3700);
FORCEADD GND..1
(9000 850);
FORCEPROP 3 LASTPIN (9000 900) SIG_NAME GND\g
J 0
(9010 910);
DISPLAY 0.659574 (9010 910);
PAINT MONO (9010 910);
DISPLAY INVISIBLE (9010 910);
FORCEPROP 1 LAST PATH I82
J 0
(9075 850);
DISPLAY 0.872340 (9075 850);
PAINT AQUA (9075 850);
DISPLAY INVISIBLE (9075 850);
FORCEPROP 1 LAST SIZE 1B
J 0
(9075 800);
DISPLAY 0.893617 (9075 800);
PAINT GREEN (9075 800);
DISPLAY INVISIBLE (9075 800);
FORCEPROP 2 LAST CDS_LIB mstr_symbols
J 0
(9000 850);
PAINT ORANGE (9000 850);
DISPLAY INVISIBLE (9000 850);
FORCEPROP 1 LAST VOLTAGE 0
J 0
(9000 850);
PAINT SKYBLUE (9000 850);
DISPLAY INVISIBLE (9000 850);
FORCEPROP 2 LAST BOM_COST MEM_VRD_PVPP_AB
J 0
(8675 925);
PAINT MONO (8675 925);
DISPLAY INVISIBLE (8675 925);
FORCEPROP 2 LAST ROOM VCCP_CPU0_VR
J 0
(8450 925);
PAINT ORANGE (8450 925);
DISPLAY INVISIBLE (8450 925);
FORCEPROP 1 LAST BODY_TYPE PLUMBING
J 0
(8955 807);
DISPLAY 0.340426 (8955 807);
PAINT GREEN (8955 807);
DISPLAY INVISIBLE (8955 807);
FORCEPROP 1 LAST HDL_POWER GND
J 0
(9000 1000);
DISPLAY 0.893617 (9000 1000);
PAINT GREEN (9000 1000);
DISPLAY INVISIBLE (9000 1000);
FORCEADD OFFPAGE..1
(7900 1175);
FORCEPROP 2 LAST $XR0 123 
J 0
(7648 1175);
DISPLAY 0.638298 (7648 1175);
PAINT MONO (7648 1175);
FORCEPROP 2 LAST PATH I85
J 0
(7950 1250);
DISPLAY 1.021277 (7950 1250);
PAINT ORANGE (7950 1250);
DISPLAY INVISIBLE (7950 1250);
FORCEPROP 2 LAST CDS_LIB mstr_standard
J 0
(7900 1175);
PAINT ORANGE (7900 1175);
DISPLAY INVISIBLE (7900 1175);
FORCEPROP 1 LAST OFFPAGE TRUE
J 0
(8225 1050);
DISPLAY 1.170213 (8225 1050);
PAINT GREEN (8225 1050);
DISPLAY INVISIBLE (8225 1050);
FORCEPROP 1 LAST COMMENT_BODY TRUE
J 0
(8025 1075);
DISPLAY 1.170213 (8025 1075);
PAINT GREEN (8025 1075);
DISPLAY INVISIBLE (8025 1075);
FORCEADD OFFPAGE..1
(7900 900);
FORCEPROP 2 LAST $XR0 123 
J 0
(7648 900);
DISPLAY 0.638298 (7648 900);
PAINT MONO (7648 900);
FORCEPROP 2 LAST PATH I86
J 0
(7950 975);
DISPLAY 1.021277 (7950 975);
PAINT ORANGE (7950 975);
DISPLAY INVISIBLE (7950 975);
FORCEPROP 2 LAST CDS_LIB mstr_standard
J 0
(7900 900);
PAINT ORANGE (7900 900);
DISPLAY INVISIBLE (7900 900);
FORCEPROP 2 LAST BOM_COST MEM_VRD_PVPP_AB
J 0
(7625 950);
PAINT MONO (7625 950);
DISPLAY INVISIBLE (7625 950);
FORCEPROP 1 LAST OFFPAGE TRUE
J 0
(8225 775);
DISPLAY 0.893617 (8225 775);
PAINT GREEN (8225 775);
DISPLAY INVISIBLE (8225 775);
FORCEPROP 1 LAST COMMENT_BODY TRUE
J 0
(8025 800);
DISPLAY 0.893617 (8025 800);
PAINT GREEN (8025 800);
DISPLAY INVISIBLE (8025 800);
FORCEADD PVNN_PCH_STBY..1
(9550 1500);
FORCEPROP 3 LASTPIN (9550 1450) SIG_NAME PVNN_PCH_STBY\g
J 0
(9560 1460);
DISPLAY 0.659574 (9560 1460);
PAINT MONO (9560 1460);
DISPLAY INVISIBLE (9560 1460);
FORCEPROP 1 LAST PATH I87
J 0
(9600 1525);
DISPLAY 0.872340 (9600 1525);
PAINT AQUA (9600 1525);
DISPLAY INVISIBLE (9600 1525);
FORCEPROP 2 LAST ROOM PVCCIO_CPU0
J 0
(9550 1600);
DISPLAY 3.127660 (9550 1600);
PAINT WHITE (9550 1600);
DISPLAY INVISIBLE (9550 1600);
FORCEPROP 2 LAST CDS_LIB mstr_symbols
J 0
(9550 1500);
PAINT ORANGE (9550 1500);
DISPLAY INVISIBLE (9550 1500);
FORCEPROP 2 LAST BOM_COST PROC_VRD_PVCCIO_CPU0
J 0
(9550 1600);
DISPLAY 2.340426 (9550 1600);
PAINT WHITE (9550 1600);
DISPLAY INVISIBLE (9550 1600);
FORCEPROP 1 LAST VOLTAGE 1.0V
J 0
(9505 1457);
DISPLAY 0.340426 (9505 1457);
PAINT SKYBLUE (9505 1457);
DISPLAY INVISIBLE (9505 1457);
FORCEPROP 1 LAST BODY_TYPE PLUMBING
J 0
(9505 1457);
DISPLAY 0.340426 (9505 1457);
PAINT GREEN (9505 1457);
DISPLAY INVISIBLE (9505 1457);
FORCEPROP 1 LAST HDL_POWER PVNN_PCH_STBY
J 1
(9550 1550);
DISPLAY 0.872340 (9550 1550);
PAINT GREEN (9550 1550);
DISPLAY INVISIBLE (9550 1550);
FORCEADD OFFPAGE..2
(10150 1175);
FORCEPROP 2 LAST $XR0 235 
J 0
(10339 1175);
DISPLAY 0.638298 (10339 1175);
PAINT MONO (10339 1175);
FORCEPROP 2 LAST PATH I88
J 0
(10325 1250);
DISPLAY 1.021277 (10325 1250);
PAINT ORANGE (10325 1250);
DISPLAY INVISIBLE (10325 1250);
FORCEPROP 2 LAST BOM_COST PROC_VRD_PVCCIO_CPU0
J 0
(10350 1225);
DISPLAY 2.340426 (10350 1225);
PAINT WHITE (10350 1225);
DISPLAY INVISIBLE (10350 1225);
FORCEPROP 2 LAST CDS_LIB mstr_standard
J 0
(10150 1175);
PAINT MONO (10150 1175);
DISPLAY INVISIBLE (10150 1175);
FORCEPROP 2 LAST ROOM PVCCIO_CPU0
J 0
(9750 1250);
DISPLAY 3.127660 (9750 1250);
PAINT WHITE (9750 1250);
DISPLAY INVISIBLE (9750 1250);
FORCEPROP 1 LAST OFFPAGE TRUE
J 0
(10475 1050);
PAINT GREEN (10475 1050);
DISPLAY INVISIBLE (10475 1050);
FORCEPROP 1 LAST COMMENT_BODY TRUE
J 0
(10105 1080);
DISPLAY 2.787234 (10105 1080);
PAINT PEACH (10105 1080);
DISPLAY INVISIBLE (10105 1080);
FORCEADD OFFPAGE..2
(10150 950);
FORCEPROP 2 LAST $XR0 235 
J 0
(10339 950);
DISPLAY 0.638298 (10339 950);
PAINT MONO (10339 950);
FORCEPROP 2 LAST PATH I89
J 0
(10325 1025);
DISPLAY 1.021277 (10325 1025);
PAINT ORANGE (10325 1025);
DISPLAY INVISIBLE (10325 1025);
FORCEPROP 2 LAST ROOM PVCCIO_CPU0
J 0
(9750 1025);
DISPLAY 3.127660 (9750 1025);
PAINT WHITE (9750 1025);
DISPLAY INVISIBLE (9750 1025);
FORCEPROP 2 LAST BOM_COST PROC_VRD_PVCCIO_CPU0
J 0
(10350 1000);
DISPLAY 2.340426 (10350 1000);
PAINT WHITE (10350 1000);
DISPLAY INVISIBLE (10350 1000);
FORCEPROP 2 LAST CDS_LIB mstr_standard
J 0
(10150 950);
PAINT MONO (10150 950);
DISPLAY INVISIBLE (10150 950);
FORCEPROP 1 LAST OFFPAGE TRUE
J 0
(10475 825);
PAINT GREEN (10475 825);
DISPLAY INVISIBLE (10475 825);
FORCEPROP 1 LAST COMMENT_BODY TRUE
J 0
(10105 855);
DISPLAY 2.787234 (10105 855);
PAINT PEACH (10105 855);
DISPLAY INVISIBLE (10105 855);
FORCEADD CAP..1
(11725 3775);
FORCEPROP 1 LASTPIN (11725 3875) $PN 1
J 0
(11735 3855);
DISPLAY 0.617021 (11735 3855);
PAINT WHITE (11735 3855);
FORCEPROP 1 LASTPIN (11725 3675) $PN 2
J 0
(11735 3655);
DISPLAY 0.617021 (11735 3655);
PAINT WHITE (11735 3655);
FORCEPROP 1 LAST LOCATION C7A30
J 0
(11775 3875);
DISPLAY 0.617021 (11775 3875);
PAINT AQUA (11775 3875);
FORCEPROP 1 LAST VALUE 22UF
J 0
(11775 3825);
DISPLAY 0.617021 (11775 3825);
PAINT SKYBLUE (11775 3825);
FORCEPROP 1 LAST MATERIAL X6S
J 0
(11775 3675);
DISPLAY 0.617021 (11775 3675);
PAINT SKYBLUE (11775 3675);
FORCEPROP 1 LAST PACK_TYPE 0805LF
J 0
(11775 3575);
DISPLAY 0.617021 (11775 3575);
PAINT SKYBLUE (11775 3575);
FORCEPROP 1 LAST VOLTAGE 4V
J 0
(11775 3775);
DISPLAY 0.617021 (11775 3775);
PAINT SKYBLUE (11775 3775);
FORCEPROP 1 LAST TOLERANCE 20%
J 0
(11775 3725);
DISPLAY 0.617021 (11775 3725);
PAINT SKYBLUE (11775 3725);
FORCEPROP 1 LAST PART_NUMBER C95333-002
J 0
(11775 3625);
DISPLAY 0.617021 (11775 3625);
PAINT BLUE (11775 3625);
FORCEPROP 2 LAST CDS_LIB mstr_discrete
J 0
(11725 3775);
DISPLAY 1.617021 (11725 3775);
PAINT ORANGE (11725 3775);
DISPLAY INVISIBLE (11725 3775);
FORCEPROP 2 LAST ROOM PVNN_PCH_STBY
J 0
(11775 3925);
DISPLAY 2.340426 (11775 3925);
PAINT WHITE (11775 3925);
DISPLAY INVISIBLE (11775 3925);
FORCEPROP 1 LAST PATH I9
J 0
(11775 3925);
DISPLAY 0.978723 (11775 3925);
PAINT WHITE (11775 3925);
DISPLAY INVISIBLE (11775 3925);
FORCEPROP 2 LAST CDS_LOCATION C7A30
J 0
(11775 3875);
DISPLAY 0.617021 (11775 3875);
PAINT AQUA (11775 3875);
DISPLAY INVISIBLE (11775 3875);
FORCEPROP 2 LAST SEC 1
J 0
(11780 3975);
DISPLAY 1.106383 (11780 3975);
PAINT MONO (11780 3975);
DISPLAY INVISIBLE (11780 3975);
FORCEPROP 2 LAST BOM_COST PROC_VRD_PVCCIO_CPU0
J 0
(11775 3925);
DISPLAY 2.340426 (11775 3925);
PAINT WHITE (11775 3925);
DISPLAY INVISIBLE (11775 3925);
FORCEPROP 2 LAST SEC_TYPE 0805LF
J 0
(11780 3975);
DISPLAY 1.659574 (11780 3975);
PAINT ORANGE (11780 3975);
DISPLAY INVISIBLE (11780 3975);
FORCEADD RES..1
(9200 1400);
FORCEPROP 1 LASTPIN (9100 1400) $PN 1
J 0
(9112 1412);
DISPLAY 0.787234 (9112 1412);
PAINT ORANGE (9112 1412);
FORCEPROP 1 LAST LOCATION R7A13
J 0
(9000 1475);
DISPLAY 0.617021 (9000 1475);
PAINT AQUA (9000 1475);
FORCEPROP 1 LAST MATERIAL CHIP
J 0
(9150 1475);
DISPLAY 0.617021 (9150 1475);
PAINT SKYBLUE (9150 1475);
FORCEPROP 1 LAST PART_NUMBER G21796-017
J 0
(9050 1300);
DISPLAY 0.617021 (9050 1300);
PAINT BLUE (9050 1300);
FORCEPROP 1 LAST PACK_TYPE 0402
J 0
(9325 1350);
DISPLAY 0.617021 (9325 1350);
PAINT SKYBLUE (9325 1350);
FORCEPROP 1 LAST TOLERANCE 1%
J 0
(9250 1350);
DISPLAY 0.617021 (9250 1350);
PAINT SKYBLUE (9250 1350);
FORCEPROP 1 LAST VALUE 100.0
J 2
(9200 1350);
DISPLAY 0.617021 (9200 1350);
PAINT SKYBLUE (9200 1350);
FORCEPROP 1 LASTPIN (9300 1400) $PN 2
J 0
(9262 1412);
DISPLAY 0.787234 (9262 1412);
PAINT ORANGE (9262 1412);
FORCEPROP 1 LAST WATTAGE 1/16W
J 2
(9425 1475);
DISPLAY 0.617021 (9425 1475);
PAINT SKYBLUE (9425 1475);
FORCEPROP 2 LAST SEC_TYPE 0402
J 0
(9150 1600);
DISPLAY 1.021277 (9150 1600);
PAINT ORANGE (9150 1600);
DISPLAY INVISIBLE (9150 1600);
FORCEPROP 2 LAST SEC 1
J 0
(9150 1600);
PAINT MONO (9150 1600);
DISPLAY INVISIBLE (9150 1600);
FORCEPROP 0 LAST ROOM P1V05_PCH_STBY
J 0
(9250 1625);
DISPLAY 1.021277 (9250 1625);
PAINT ORANGE (9250 1625);
DISPLAY INVISIBLE (9250 1625);
FORCEPROP 0 LAST BOM_COST P1V05_PCH_STBY
J 0
(9250 1725);
DISPLAY 1.021277 (9250 1725);
PAINT ORANGE (9250 1725);
DISPLAY INVISIBLE (9250 1725);
FORCEPROP 2 LAST CDS_LOCATION R7A13
J 0
(9225 1450);
DISPLAY 0.617021 (9225 1450);
PAINT AQUA (9225 1450);
DISPLAY INVISIBLE (9225 1450);
FORCEPROP 1 LAST PATH I90
J 0
(9150 1550);
DISPLAY 0.978723 (9150 1550);
PAINT WHITE (9150 1550);
DISPLAY INVISIBLE (9150 1550);
FORCEPROP 0 LAST SPOF TRUE
J 0
(9150 1600);
DISPLAY 1.021277 (9150 1600);
PAINT ORANGE (9150 1600);
DISPLAY INVISIBLE (9150 1600);
FORCEPROP 2 LAST CDS_LIB mstr_discrete
J 0
(9200 1400);
PAINT MONO (9200 1400);
DISPLAY INVISIBLE (9200 1400);
FORCEADD RES..1
(9200 950);
FORCEPROP 1 LAST PACK_TYPE 0402
J 0
(9350 850);
DISPLAY 0.617021 (9350 850);
PAINT SKYBLUE (9350 850);
FORCEPROP 1 LAST MATERIAL CHIP
J 0
(9225 850);
DISPLAY 0.617021 (9225 850);
PAINT SKYBLUE (9225 850);
FORCEPROP 1 LAST WATTAGE 1/16W
J 2
(9200 850);
DISPLAY 0.617021 (9200 850);
PAINT SKYBLUE (9200 850);
FORCEPROP 1 LAST TOLERANCE 5%
J 0
(9250 900);
DISPLAY 0.617021 (9250 900);
PAINT SKYBLUE (9250 900);
FORCEPROP 1 LASTPIN (9100 950) $PN 1
J 0
(9112 962);
DISPLAY 0.787234 (9112 962);
PAINT ORANGE (9112 962);
FORCEPROP 1 LAST PART_NUMBER G21497-005
J 0
(9050 1000);
DISPLAY 0.617021 (9050 1000);
PAINT BLUE (9050 1000);
FORCEPROP 1 LASTPIN (9300 950) $PN 2
J 0
(9262 962);
DISPLAY 0.787234 (9262 962);
PAINT ORANGE (9262 962);
FORCEPROP 1 LAST VALUE 0.0
J 2
(9200 900);
DISPLAY 0.617021 (9200 900);
PAINT SKYBLUE (9200 900);
FORCEPROP 1 LAST LOCATION R7A18
J 0
(9150 1050);
DISPLAY 0.617021 (9150 1050);
PAINT AQUA (9150 1050);
FORCEPROP 1 LAST PATH I92
J 0
(9150 1100);
DISPLAY 0.978723 (9150 1100);
PAINT WHITE (9150 1100);
DISPLAY INVISIBLE (9150 1100);
FORCEPROP 0 LAST ROOM P1V05_PCH_STBY
J 0
(9250 1175);
DISPLAY 1.021277 (9250 1175);
PAINT ORANGE (9250 1175);
DISPLAY INVISIBLE (9250 1175);
FORCEPROP 0 LAST SPOF TRUE
J 0
(9150 1150);
DISPLAY 1.021277 (9150 1150);
PAINT ORANGE (9150 1150);
DISPLAY INVISIBLE (9150 1150);
FORCEPROP 2 LAST CDS_LOCATION R7A18
J 0
(9150 1050);
DISPLAY 0.617021 (9150 1050);
PAINT AQUA (9150 1050);
DISPLAY INVISIBLE (9150 1050);
FORCEPROP 0 LAST BOM_COST P1V05_PCH_STBY
J 0
(9250 1275);
DISPLAY 1.021277 (9250 1275);
PAINT ORANGE (9250 1275);
DISPLAY INVISIBLE (9250 1275);
FORCEPROP 2 LAST CDS_LIB mstr_discrete
J 0
(9200 950);
PAINT MONO (9200 950);
DISPLAY INVISIBLE (9200 950);
FORCEPROP 2 LAST SEC 1
J 0
(9150 1150);
PAINT MONO (9150 1150);
DISPLAY INVISIBLE (9150 1150);
FORCEPROP 2 LAST SEC_TYPE 0402
J 0
(9150 1150);
DISPLAY 1.021277 (9150 1150);
PAINT ORANGE (9150 1150);
DISPLAY INVISIBLE (9150 1150);
FORCEADD RES..1
(8725 1175);
FORCEPROP 2 LAST NO_XNET_CONNECTION 1
J 0
(8550 1250);
PAINT MONO (8550 1250);
FORCEPROP 1 LAST VALUE 10.0
J 2
(8700 1225);
DISPLAY 0.617021 (8700 1225);
PAINT SKYBLUE (8700 1225);
FORCEPROP 1 LAST PACK_TYPE 0402
J 0
(8775 1100);
DISPLAY 0.617021 (8775 1100);
PAINT SKYBLUE (8775 1100);
FORCEPROP 1 LAST MATERIAL CHIP
J 0
(8875 1200);
DISPLAY 0.638298 (8875 1200);
PAINT SKYBLUE (8875 1200);
FORCEPROP 1 LASTPIN (8825 1175) $PN 2
J 0
(8787 1187);
DISPLAY 0.617021 (8787 1187);
PAINT ORANGE (8787 1187);
FORCEPROP 1 LAST WATTAGE 1/16W
J 2
(8750 1100);
DISPLAY 0.617021 (8750 1100);
PAINT SKYBLUE (8750 1100);
FORCEPROP 1 LASTPIN (8625 1175) $PN 1
J 0
(8637 1187);
DISPLAY 0.617021 (8637 1187);
PAINT ORANGE (8637 1187);
FORCEPROP 1 LAST TOLERANCE 1%
J 0
(8750 1225);
DISPLAY 0.617021 (8750 1225);
PAINT SKYBLUE (8750 1225);
FORCEPROP 1 LAST PART_NUMBER G21796-066
J 0
(8600 1275);
DISPLAY 0.617021 (8600 1275);
PAINT BLUE (8600 1275);
FORCEPROP 1 LAST LOCATION R7A19
J 0
(8650 1325);
DISPLAY 0.617021 (8650 1325);
PAINT AQUA (8650 1325);
FORCEPROP 2 LAST BOM_COST P1V05_PCH_STBY
J 0
(8800 1325);
PAINT MONO (8800 1325);
DISPLAY INVISIBLE (8800 1325);
FORCEPROP 2 LAST CDS_LIB mstr_discrete
J 0
(8725 1175);
PAINT MONO (8725 1175);
DISPLAY INVISIBLE (8725 1175);
FORCEPROP 0 LAST SPOF TRUE
J 0
(8650 1425);
DISPLAY 1.021277 (8650 1425);
PAINT ORANGE (8650 1425);
DISPLAY INVISIBLE (8650 1425);
FORCEPROP 2 LAST SEC_TYPE 0402
J 0
(8525 1400);
DISPLAY 1.021277 (8525 1400);
PAINT ORANGE (8525 1400);
DISPLAY INVISIBLE (8525 1400);
FORCEPROP 2 LAST SEC 1
J 0
(8525 1400);
PAINT MONO (8525 1400);
DISPLAY INVISIBLE (8525 1400);
FORCEPROP 2 LAST CDS_LOCATION R7A19
J 0
(8650 1325);
DISPLAY 0.617021 (8650 1325);
PAINT AQUA (8650 1325);
DISPLAY INVISIBLE (8650 1325);
FORCEPROP 1 LAST PATH I93
J 0
(8675 1325);
DISPLAY 0.978723 (8675 1325);
PAINT WHITE (8675 1325);
DISPLAY INVISIBLE (8675 1325);
FORCEPROP 2 LAST ROOM P1V05_PCH_STBY
J 0
(8675 1275);
PAINT ORANGE (8675 1275);
DISPLAY INVISIBLE (8675 1275);
FORCEADD RES..1
(8750 900);
FORCEPROP 1 LASTPIN (8650 900) $PN 1
J 0
(8662 912);
DISPLAY 0.617021 (8662 912);
PAINT ORANGE (8662 912);
FORCEPROP 1 LAST PACK_TYPE 0402
J 0
(8775 800);
DISPLAY 0.617021 (8775 800);
PAINT SKYBLUE (8775 800);
FORCEPROP 1 LAST WATTAGE 1/16W
J 2
(8750 800);
DISPLAY 0.617021 (8750 800);
PAINT SKYBLUE (8750 800);
FORCEPROP 1 LAST TOLERANCE 1%
J 0
(8800 850);
DISPLAY 0.617021 (8800 850);
PAINT SKYBLUE (8800 850);
FORCEPROP 1 LAST VALUE 10.0
J 2
(8725 850);
DISPLAY 0.617021 (8725 850);
PAINT SKYBLUE (8725 850);
FORCEPROP 1 LAST MATERIAL CHIP
J 0
(8900 800);
DISPLAY 0.638298 (8900 800);
PAINT SKYBLUE (8900 800);
FORCEPROP 2 LAST NO_XNET_CONNECTION 1
J 0
(8575 1000);
PAINT MONO (8575 1000);
FORCEPROP 1 LASTPIN (8850 900) $PN 2
J 0
(8812 912);
DISPLAY 0.617021 (8812 912);
PAINT ORANGE (8812 912);
FORCEPROP 1 LAST PART_NUMBER G21796-066
J 0
(8625 950);
DISPLAY 0.617021 (8625 950);
PAINT BLUE (8625 950);
FORCEPROP 1 LAST LOCATION R7A14
J 0
(8700 1000);
DISPLAY 0.617021 (8700 1000);
PAINT AQUA (8700 1000);
FORCEPROP 2 LAST BOM_COST P1V05_PCH_STBY
J 0
(8825 1050);
PAINT MONO (8825 1050);
DISPLAY INVISIBLE (8825 1050);
FORCEPROP 0 LAST SPOF TRUE
J 0
(8700 1100);
DISPLAY 1.021277 (8700 1100);
PAINT ORANGE (8700 1100);
DISPLAY INVISIBLE (8700 1100);
FORCEPROP 2 LAST SEC_TYPE 0402
J 0
(8550 1125);
DISPLAY 1.021277 (8550 1125);
PAINT ORANGE (8550 1125);
DISPLAY INVISIBLE (8550 1125);
FORCEPROP 1 LAST PATH I94
J 0
(8700 1050);
DISPLAY 0.978723 (8700 1050);
PAINT WHITE (8700 1050);
DISPLAY INVISIBLE (8700 1050);
FORCEPROP 2 LAST SEC 1
J 0
(8550 1125);
PAINT MONO (8550 1125);
DISPLAY INVISIBLE (8550 1125);
FORCEPROP 2 LAST ROOM P1V05_PCH_STBY
J 0
(8700 1000);
PAINT ORANGE (8700 1000);
DISPLAY INVISIBLE (8700 1000);
FORCEPROP 2 LAST CDS_LOCATION R7A14
J 0
(8700 1000);
DISPLAY 0.617021 (8700 1000);
PAINT AQUA (8700 1000);
DISPLAY INVISIBLE (8700 1000);
FORCEPROP 2 LAST CDS_LIB mstr_discrete
J 0
(8750 900);
PAINT MONO (8750 900);
DISPLAY INVISIBLE (8750 900);
FORCEADD VCC_CORE..1
(6275 4900);
FORCEPROP 3 LASTPIN (6275 4850) SIG_NAME VR_FET_SW_P12V_STBY_PVDDQ_DEF\g
J 0
(6285 4860);
DISPLAY 0.659574 (6285 4860);
PAINT MONO (6285 4860);
DISPLAY INVISIBLE (6285 4860);
FORCEPROP 1 LAST HDL_POWER VR_FET_SW_P12V_STBY_PVDDQ_DEF
J 1
(6275 4950);
DISPLAY 0.617021 (6275 4950);
PAINT GREEN (6275 4950);
FORCEPROP 2 LAST CDS_LIB mstr_symbols
J 0
(6275 4900);
PAINT ORANGE (6275 4900);
DISPLAY INVISIBLE (6275 4900);
FORCEPROP 1 LAST PATH I95
J 0
(6325 4925);
DISPLAY 0.872340 (6325 4925);
PAINT AQUA (6325 4925);
DISPLAY INVISIBLE (6325 4925);
FORCEADD VCC_CORE..1
(6250 3125);
FORCEPROP 3 LASTPIN (6250 3075) SIG_NAME VR_FET_SW_P12V_STBY_PVDDQ_DEF\g
J 0
(6260 3085);
DISPLAY 0.659574 (6260 3085);
PAINT MONO (6260 3085);
DISPLAY INVISIBLE (6260 3085);
FORCEPROP 1 LAST HDL_POWER VR_FET_SW_P12V_STBY_PVDDQ_DEF
J 1
(6250 3175);
DISPLAY 0.617021 (6250 3175);
PAINT GREEN (6250 3175);
FORCEPROP 2 LAST CDS_LIB mstr_symbols
J 0
(6250 3125);
PAINT ORANGE (6250 3125);
DISPLAY INVISIBLE (6250 3125);
FORCEPROP 1 LAST PATH I96
J 0
(6300 3150);
DISPLAY 0.872340 (6300 3150);
PAINT AQUA (6300 3150);
DISPLAY INVISIBLE (6300 3150);
FORCEADD VCC_CORE..1
(12700 1400);
FORCEPROP 3 LASTPIN (12700 1350) SIG_NAME VR_FET_SW_P12V_STBY_PVDDQ_DEF\g
J 0
(12710 1360);
DISPLAY 0.659574 (12710 1360);
PAINT MONO (12710 1360);
DISPLAY INVISIBLE (12710 1360);
FORCEPROP 1 LAST HDL_POWER VR_FET_SW_P12V_STBY_PVDDQ_DEF
J 1
(12700 1450);
DISPLAY 0.617021 (12700 1450);
PAINT GREEN (12700 1450);
FORCEPROP 2 LAST CDS_LIB mstr_symbols
J 0
(12700 1400);
PAINT ORANGE (12700 1400);
DISPLAY INVISIBLE (12700 1400);
FORCEPROP 1 LAST PATH I97
J 0
(12750 1425);
DISPLAY 0.872340 (12750 1425);
PAINT AQUA (12750 1425);
DISPLAY INVISIBLE (12750 1425);
FORCEADD INTEL_CORP_BPAGE..1
(13100 225);
FORCEPROP 1 LAST CDS_CON_LAST_MODIFIED Fri Jun 16 17:49:24 2017
J 0
(11675 550);
PAINT GREEN (11675 550);
DISPLAY INVISIBLE (11675 550);
FORCEPROP 1 LAST CUSTOM_TXT_CDS <CURRENT_DESIGN_SHEET> OF <TOTAL_DESIGN_SHEETS>
J 0
(12600 250);
PAINT ORANGE (12600 250);
FORCEPROP 1 LAST CUSTOM_TXT_CDS <CON_LAST_MODIFIED>
J 0
(9100 325);
PAINT ORANGE (9100 325);
FORCEPROP 2 LAST CUSTOM_TXT_CDS <XR_PAGE_TITLE>
J 0
(5210 5475);
DISPLAY 0.638298 (5210 5475);
PAINT PINK (5210 5475);
DISPLAY INVISIBLE (5210 5475);
FORCEPROP 1 LAST SCH_TITLE PVNN P1V05 PCH STBY VR (2 OF 2)
J 0
(5250 350);
DISPLAY 1.212766 (5250 350);
PAINT ORANGE (5250 350);
FORCEPROP 2 LAST CDS_LIB mstr_symbols
J 0
(13100 225);
PAINT ORANGE (13100 225);
DISPLAY INVISIBLE (13100 225);
FORCEPROP 2 LAST PAGE_BORDER TRUE
J 0
(5210 5475);
DISPLAY 0.851064 (5210 5475);
PAINT PINK (5210 5475);
DISPLAY INVISIBLE (5210 5475);
FORCEPROP 1 LAST COMMENT_BODY TRUE
J 0
(13112 237);
DISPLAY 0.468085 (13112 237);
PAINT GREEN (13112 237);
DISPLAY INVISIBLE (13112 237);
FORCEPROP 2 LAST CDS_XR_PAGE_TITLE CR-236 : @BASEBOARD_FAB2_LIB.BASEBOARD_FAB2(SCH_1):PAGE236
J 0
(5210 5475);
DISPLAY 0.638298 (5210 5475);
PAINT PINK (5210 5475);
DISPLAY INVISIBLE (5210 5475);
FORCEADD DNS..2
(12155 2695);
PAINT RED (12155 2695);
FORCEPROP 2 LAST CDS_LIB mstr_misc
J 0
(12155 2695);
PAINT ORANGE (12155 2695);
DISPLAY INVISIBLE (12155 2695);
FORCEPROP 1 LAST COMMENT_BODY TRUE
R 1
J 0
(12230 2470);
DISPLAY 0.872340 (12230 2470);
PAINT GREEN (12230 2470);
DISPLAY INVISIBLE (12230 2470);
FORCEADD DNS..2
(12130 4445);
PAINT RED (12130 4445);
FORCEPROP 2 LAST CDS_LIB mstr_misc
J 0
(12130 4445);
PAINT ORANGE (12130 4445);
DISPLAY INVISIBLE (12130 4445);
FORCEPROP 1 LAST COMMENT_BODY TRUE
R 1
J 0
(12205 4220);
DISPLAY 0.872340 (12205 4220);
PAINT GREEN (12205 4220);
DISPLAY INVISIBLE (12205 4220);
FORCEADD DNS..2
(7155 1045);
PAINT RED (7155 1045);
FORCEPROP 2 LAST CDS_LIB mstr_misc
J 0
(7155 1045);
PAINT ORANGE (7155 1045);
DISPLAY INVISIBLE (7155 1045);
FORCEPROP 1 LAST COMMENT_BODY TRUE
R 1
J 0
(7230 820);
DISPLAY 0.872340 (7230 820);
PAINT GREEN (7230 820);
DISPLAY INVISIBLE (7230 820);
WIRE 16 -1 (10450 3650)(10450 3725);
WIRE 16 -1 (10450 3725)(10450 3775);
WIRE 16 -1 (10450 3725)(10350 3725);
WIRE 16 -1 (10450 3775)(10450 3825);
WIRE 16 -1 (10450 3775)(10350 3775);
WIRE 16 -1 (10450 3825)(10450 3875);
WIRE 16 -1 (10450 3825)(10350 3825);
WIRE 16 -1 (10350 3875)(10450 3875);
WIRE 16 -1 (12125 4350)(12125 4250);
WIRE 16 -1 (12150 2600)(12150 2500);
WIRE 16 -1 (8525 5050)(8525 5100);
WIRE 16 -1 (8525 4625)(8525 5050);
WIRE 16 -1 (8525 5050)(8125 5050);
WIRE 16 -1 (8125 5050)(7800 5050);
WIRE 16 -1 (8125 4675)(8125 5050);
WIRE 16 -1 (9225 4625)(8525 4625);
WIRE 16 -1 (9225 4525)(9225 4625);
WIRE 16 -1 (9350 4625)(9225 4625);
WIRE 16 -1 (7800 4600)(7800 5050);
WIRE 16 -1 (7525 5050)(7800 5050);
WIRE 16 -1 (9350 4525)(9225 4525);
WIRE 16 -1 (9125 1925)(9125 1825);
WIRE 16 -1 (9125 3675)(9125 3550);
WIRE 16 -1 (10925 4150)(10925 4200);
WIRE 16 -1 (10900 2500)(10900 2475);
WIRE 16 -1 (11050 1700)(11050 1725);
WIRE 16 -1 (12700 900)(12700 775);
WIRE 16 -1 (12400 900)(12400 775);
WIRE 16 -1 (12100 900)(12100 775);
WIRE 16 -1 (11800 900)(11800 775);
WIRE 16 -1 (11450 900)(11450 775);
WIRE 16 -1 (11150 900)(11150 775);
WIRE 16 -1 (10850 900)(10850 775);
WIRE 16 -1 (10550 900)(10550 775);
WIRE 16 -1 (6000 4200)(6000 4250);
WIRE 16 -1 (6000 4250)(6275 4250);
WIRE 16 -1 (6000 4450)(6000 4250);
WIRE 16 -1 (6525 4250)(6275 4250);
WIRE 16 -1 (6275 4400)(6275 4250);
WIRE 16 -1 (6775 4250)(6525 4250);
WIRE 16 -1 (6525 4450)(6525 4250);
WIRE 16 -1 (7025 4250)(6775 4250);
WIRE 16 -1 (6775 4400)(6775 4250);
WIRE 16 -1 (7300 4250)(7025 4250);
WIRE 16 -1 (7025 4450)(7025 4250);
WIRE 16 -1 (7300 4250)(7800 4250);
WIRE 16 -1 (7300 4400)(7300 4250);
WIRE 16 -1 (8125 4250)(7800 4250);
WIRE 16 -1 (7800 4450)(7800 4250);
WIRE 16 -1 (8125 4475)(8125 4250);
WIRE 16 -1 (6025 2350)(6025 2500);
WIRE 16 -1 (6025 2500)(6250 2500);
WIRE 16 -1 (6025 2775)(6025 2500);
WIRE 16 -1 (6475 2500)(6250 2500);
WIRE 16 -1 (6250 2700)(6250 2500);
WIRE 16 -1 (6700 2500)(6475 2500);
WIRE 16 -1 (6475 2775)(6475 2500);
WIRE 16 -1 (6700 2500)(6925 2500);
WIRE 16 -1 (6700 2700)(6700 2500);
WIRE 16 -1 (6925 2500)(7175 2500);
WIRE 16 -1 (6925 2775)(6925 2500);
WIRE 16 -1 (7175 2500)(7625 2500);
WIRE 16 -1 (7175 2700)(7175 2500);
WIRE 16 -1 (8000 2500)(7625 2500);
WIRE 16 -1 (7625 2700)(7625 2500);
WIRE 16 -1 (8000 2775)(8000 2500);
WIRE 16 -1 (8525 3300)(8525 3375);
WIRE 16 -1 (8525 2875)(8525 3300);
WIRE 16 -1 (8000 3300)(8525 3300);
WIRE 16 -1 (8000 3300)(7625 3300);
WIRE 16 -1 (8000 2975)(8000 3300);
WIRE 16 -1 (8525 2875)(9275 2875);
WIRE 16 -1 (9275 2775)(9275 2875);
WIRE 16 -1 (9375 2875)(9275 2875);
WIRE 16 -1 (7625 2850)(7625 3300);
WIRE 16 -1 (7425 3300)(7625 3300);
WIRE 16 -1 (9375 2775)(9275 2775);
WIRE 16 -1 (10450 1925)(10450 1975);
WIRE 16 -1 (10450 1975)(10450 2025);
WIRE 16 -1 (10450 1975)(10375 1975);
WIRE 16 -1 (10450 2025)(10450 2075);
WIRE 16 -1 (10450 2025)(10375 2025);
WIRE 16 -1 (10450 2075)(10450 2125);
WIRE 16 -1 (10450 2075)(10375 2075);
WIRE 16 -1 (10375 2125)(10450 2125);
WIRE 16 -1 (11650 1875)(11650 1900);
WIRE 16 -1 (11925 1900)(11650 1900);
WIRE 16 -1 (11650 1900)(11650 1950);
WIRE 16 -1 (12175 1900)(11925 1900);
WIRE 16 -1 (11925 1950)(11925 1900);
WIRE 16 -1 (12425 1900)(12175 1900);
WIRE 16 -1 (12175 1950)(12175 1900);
WIRE 16 -1 (12700 1900)(12425 1900);
WIRE 16 -1 (12425 1950)(12425 1900);
WIRE 16 -1 (12700 1950)(12700 1900);
WIRE 16 -1 (12700 2275)(12700 2325);
WIRE 16 -1 (12425 2275)(12700 2275);
WIRE 16 -1 (12700 2150)(12700 2275);
WIRE 16 -1 (12175 2275)(12425 2275);
WIRE 16 -1 (12425 2150)(12425 2275);
WIRE 16 -1 (11925 2275)(12175 2275);
WIRE 16 -1 (12175 2150)(12175 2275);
WIRE 16 -1 (11650 2275)(11925 2275);
WIRE 16 -1 (11925 2150)(11925 2275);
WIRE 16 -1 (11600 2275)(11650 2275);
WIRE 16 -1 (11650 2150)(11650 2275);
WIRE 16 -1 (11600 1625)(11600 2275);
WIRE 16 -1 (11550 2275)(11600 2275);
WIRE 16 -1 (9275 1625)(11600 1625);
WIRE 16 -1 (9275 2675)(9275 1625);
WIRE 16 -1 (9375 2675)(9275 2675);
WIRE 16 -1 (7675 1450)(7675 1300);
WIRE 16 -1 (7675 1300)(7550 1300);
WIRE 16 -1 (7650 675)(7650 850);
WIRE 16 -1 (7650 850)(7525 850);
WIRE 16 -1 (12650 3975)(12650 4025);
WIRE 16 -1 (12600 3975)(12650 3975);
WIRE 16 -1 (12850 3975)(12650 3975);
WIRE 16 -1 (12850 3875)(12850 3975);
WIRE 16 -1 (12325 3975)(12600 3975);
WIRE 16 -1 (12600 3875)(12600 3975);
WIRE 16 -1 (12025 3975)(12325 3975);
WIRE 16 -1 (12325 3875)(12325 3975);
WIRE 16 -1 (11725 3975)(12025 3975);
WIRE 16 -1 (12025 3875)(12025 3975);
WIRE 16 -1 (11650 3975)(11725 3975);
WIRE 16 -1 (11725 3875)(11725 3975);
WIRE 16 -1 (11650 3350)(11650 3975);
WIRE 16 -1 (11525 3975)(11650 3975);
WIRE 16 -1 (9225 3350)(11650 3350);
WIRE 16 -1 (9225 4425)(9225 3350);
WIRE 16 -1 (9350 4425)(9225 4425);
WIRE 16 -1 (11725 3600)(11725 3675);
WIRE 16 -1 (12025 3600)(11725 3600);
WIRE 16 -1 (12325 3600)(12025 3600);
WIRE 16 -1 (12025 3675)(12025 3600);
WIRE 16 -1 (12600 3600)(12325 3600);
WIRE 16 -1 (12325 3675)(12325 3600);
WIRE 16 -1 (12850 3600)(12600 3600);
WIRE 16 -1 (12600 3675)(12600 3600);
WIRE 16 -1 (12850 3675)(12850 3600);
WIRE 16 -1 (9000 900)(9000 950);
WIRE 16 -1 (9000 950)(9100 950);
WIRE 16 -1 (9550 1400)(9550 1450);
WIRE 16 -1 (9300 1400)(9550 1400);
WIRE 16 -1 (6275 4850)(6275 4725);
WIRE 16 -1 (6525 4725)(6275 4725);
WIRE 16 -1 (6000 4725)(6275 4725);
WIRE 16 -1 (6275 4600)(6275 4725);
WIRE 16 -1 (6000 4650)(6000 4725);
WIRE 16 -1 (6775 4725)(6525 4725);
WIRE 16 -1 (6525 4650)(6525 4725);
WIRE 16 -1 (7025 4725)(6775 4725);
WIRE 16 -1 (6775 4600)(6775 4725);
WIRE 16 -1 (9050 4725)(7025 4725);
WIRE 16 -1 (7025 4650)(7025 4725);
WIRE 16 -1 (9050 4775)(9050 4725);
WIRE 16 -1 (9350 4725)(9050 4725);
WIRE 16 -1 (9350 4775)(9050 4775);
WIRE 16 -1 (6250 3075)(6250 3025);
WIRE 16 -1 (6475 3025)(6250 3025);
WIRE 16 -1 (6025 3025)(6250 3025);
WIRE 16 -1 (6250 2900)(6250 3025);
WIRE 16 -1 (6025 2975)(6025 3025);
WIRE 16 -1 (6700 3025)(6475 3025);
WIRE 16 -1 (6475 2975)(6475 3025);
WIRE 16 -1 (6700 3025)(6925 3025);
WIRE 16 -1 (6700 2900)(6700 3025);
WIRE 16 -1 (9200 3025)(6925 3025);
WIRE 16 -1 (6925 2975)(6925 3025);
WIRE 16 -1 (9200 3025)(9200 2975);
WIRE 16 -1 (9200 3025)(9375 3025);
WIRE 16 -1 (9375 2975)(9200 2975);
WIRE 16 -1 (12700 1200)(12700 1350);
WIRE 16 -1 (12700 1200)(12400 1200);
WIRE 16 -1 (12700 1200)(12700 1050);
WIRE 16 -1 (12400 1200)(12100 1200);
WIRE 16 -1 (12400 1200)(12400 1050);
WIRE 16 -1 (12100 1200)(11800 1200);
WIRE 16 -1 (12100 1200)(12100 1050);
WIRE 16 -1 (11800 1200)(11450 1200);
WIRE 16 -1 (11800 1050)(11800 1200);
WIRE 16 -1 (11150 1200)(11450 1200);
WIRE 16 -1 (11450 1200)(11450 1050);
WIRE 16 -1 (10850 1200)(11150 1200);
WIRE 16 -1 (11150 1200)(11150 1050);
WIRE 16 -1 (10550 1200)(10850 1200);
WIRE 16 -1 (10850 1200)(10850 1050);
WIRE 16 -1 (10550 1050)(10550 1200);
WIRE 3 2175 (7750 3850)(8300 3850);
WIRE 3 2175 (8300 4150)(8300 3850);
WIRE 3 2175 (7750 4150)(7750 3850);
WIRE 3 2175 (7750 4150)(8300 4150);
WIRE 68 -1 (11750 700)(13000 700);
WIRE 68 -1 (13000 700)(13000 1250);
WIRE 68 -1 (11750 700)(11750 1250);
WIRE 68 -1 (11750 1250)(13000 1250);
WIRE 16 -1 (8950 2175)(9375 2175);
WIRE 16 -1 (8950 1925)(8950 2175);
WIRE 16 -1 (7050 1925)(7050 2000);
WIRE 16 -1 (7050 1925)(8950 1925);
FORCEPROP 2 LAST SIG_NAME VR_P1V05_PCH_STBY_PH1_PHASE
J 0
(7090 1935);
DISPLAY 0.617021 (7090 1935);
PAINT ORANGE (7090 1935);
FORCEPROP 2 LASTPROP $XRERR UNIQUE?
J 0
(6850 1935);
DISPLAY 0.638298 (6850 1935);
PAINT MONO (6850 1935);
DISPLAY INVISIBLE (6850 1935);
WIRE 16 2175 (6850 1875)(7725 1875);
WIRE 16 2175 (7725 2400)(7725 1875);
WIRE 16 2175 (6850 2400)(6850 1875);
WIRE 16 2175 (6850 2400)(7725 2400);
WIRE 16 2175 (6725 3625)(7675 3625);
WIRE 16 2175 (7675 4125)(7675 3625);
WIRE 16 2175 (6725 4125)(6725 3625);
WIRE 16 2175 (6725 4125)(7675 4125);
WIRE 16 -1 (6600 4175)(9350 4175);
FORCEPROP 2 LAST SIG_NAME VR_PVNN_PCH_PWM1
J 0
(6600 4199);
DISPLAY 0.617021 (6600 4199);
PAINT ORANGE (6600 4199);
WIRE 16 2175 (7450 2550)(8100 2550);
WIRE 16 2175 (8100 3000)(8100 2550);
WIRE 16 2175 (7450 3000)(7450 2550);
WIRE 16 2175 (7450 3000)(8100 3000);
WIRE 16 -1 (6650 2425)(9375 2425);
FORCEPROP 2 LAST SIG_NAME VR_P1V05_PCH_STBY_PWM1
J 0
(6675 2449);
DISPLAY 0.617021 (6675 2449);
PAINT ORANGE (6675 2449);
WIRE 16 -1 (8950 2325)(8150 2325);
FORCEPROP 0 LAST SIG_NAME VR_P1V05_PCH_STBY_PH1_BOOT_R
J 0
(8265 2335);
DISPLAY 0.617021 (8265 2335);
PAINT ORANGE (8265 2335);
FORCEPROP 2 LASTPROP $XRERR UNIQUE?
J 0
(8025 2335);
DISPLAY 0.638298 (8025 2335);
PAINT MONO (8025 2335);
DISPLAY INVISIBLE (8025 2335);
WIRE 16 -1 (8950 2225)(8950 2325);
WIRE 16 -1 (9375 2225)(8950 2225);
WIRE 16 -1 (8925 3925)(9350 3925);
WIRE 16 -1 (8925 3675)(8925 3925);
WIRE 16 -1 (6975 3675)(6975 3750);
WIRE 16 -1 (6975 3675)(8925 3675);
FORCEPROP 2 LAST SIG_NAME VR_PVNN_PCH_PH1_PHASE
J 0
(7090 3685);
DISPLAY 0.617021 (7090 3685);
PAINT ORANGE (7090 3685);
FORCEPROP 2 LASTPROP $XRERR UNIQUE?
J 0
(6850 3685);
DISPLAY 0.638298 (6850 3685);
PAINT MONO (6850 3685);
DISPLAY INVISIBLE (6850 3685);
WIRE 16 -1 (8925 4050)(8125 4050);
FORCEPROP 0 LAST SIG_NAME VR_PVNN_PCH_PH1_BOOT_R
J 0
(8340 4060);
DISPLAY 0.617021 (8340 4060);
PAINT ORANGE (8340 4060);
FORCEPROP 2 LASTPROP $XRERR UNIQUE?
J 0
(8100 4060);
DISPLAY 0.638298 (8100 4060);
PAINT MONO (8100 4060);
DISPLAY INVISIBLE (8100 4060);
WIRE 16 -1 (8925 3975)(8925 4050);
WIRE 16 -1 (9350 3975)(8925 3975);
WIRE 3 2175 (10075 3375)(11175 3375);
WIRE 3 2175 (11175 4025)(11175 3375);
WIRE 3 2175 (10075 4025)(10075 3375);
WIRE 3 2175 (10075 4025)(11175 4025);
WIRE 3 682 (10450 4575)(10550 4575);
WIRE 16 -1 (12125 4625)(12125 4550);
WIRE 16 -1 (10350 4625)(12125 4625);
FORCEPROP 0 LAST SIG_NAME VR_PVNN_PCH_STBY_OCSET
J 0
(10490 4635);
DISPLAY 0.617021 (10490 4635);
PAINT ORANGE (10490 4635);
FORCEPROP 2 LASTPROP $XRERR UNIQUE?
J 0
(10250 4635);
DISPLAY 0.638298 (10250 4635);
PAINT MONO (10250 4635);
DISPLAY INVISIBLE (10250 4635);
WIRE 16 -1 (10450 4325)(10350 4325);
WIRE 16 -1 (10925 4400)(10925 4450);
WIRE 16 -1 (10925 4450)(11450 4450);
WIRE 16 -1 (10450 4450)(10450 4325);
WIRE 16 -1 (10450 4450)(10925 4450);
FORCEPROP 2 LAST SIG_NAME A_TSENSE_PVNN_PCH_TMON
J 2
(11025 4464);
DISPLAY 0.617021 (11025 4464);
PAINT ORANGE (11025 4464);
WIRE 16 -1 (9375 2525)(8475 2525);
FORCEPROP 0 LAST SIG_NAME TP_P1V05_PCH_GL_0
J 0
(8490 2535);
DISPLAY 0.617021 (8490 2535);
PAINT ORANGE (8490 2535);
FORCEPROP 2 LASTPROP $XRERR UNIQUE?
J 0
(8235 2525);
DISPLAY 0.638298 (8235 2525);
PAINT MONO (8235 2525);
DISPLAY INVISIBLE (8235 2525);
WIRE 3 2175 (9925 1650)(11100 1650);
WIRE 3 2175 (11100 2325)(11100 1650);
WIRE 3 2175 (9925 2325)(9925 1650);
WIRE 3 2175 (9925 2325)(11100 2325);
WIRE 16 -1 (10900 2700)(10900 2725);
WIRE 16 -1 (10900 2725)(11325 2725);
WIRE 16 -1 (10375 2725)(10375 2575);
WIRE 16 -1 (10375 2725)(10900 2725);
FORCEPROP 2 LAST SIG_NAME A_TSENSE_P1V05_PCH_STBY_TMON
J 0
(10400 2739);
DISPLAY 0.617021 (10400 2739);
PAINT ORANGE (10400 2739);
WIRE 3 2175 (10750 2350)(11200 2350);
WIRE 3 2175 (11200 2775)(11200 2350);
WIRE 3 2175 (10750 2775)(10750 2350);
WIRE 3 2175 (10750 2775)(11200 2775);
WIRE 16 -1 (12150 2875)(12150 2800);
WIRE 16 -1 (10375 2875)(12150 2875);
FORCEPROP 0 LAST SIG_NAME VR_P1V05_PCH_STBY_OCSET
J 0
(10525 2885);
DISPLAY 0.617021 (10525 2885);
PAINT ORANGE (10525 2885);
FORCEPROP 2 LASTPROP $XRERR UNIQUE?
J 0
(10285 2885);
DISPLAY 0.638298 (10285 2885);
PAINT MONO (10285 2885);
DISPLAY INVISIBLE (10285 2885);
WIRE 3 2175 (8825 3450)(9450 3450);
WIRE 3 2175 (9450 4025)(9450 3450);
WIRE 3 2175 (8825 4025)(8825 3450);
WIRE 3 2175 (8825 4025)(9450 4025);
WIRE 3 682 (7850 4375)(7750 4375);
WIRE 3 682 (7850 4675)(7850 4375);
WIRE 3 682 (7750 4375)(7750 4675);
WIRE 3 682 (7750 4675)(7850 4675);
WIRE 16 -1 (9125 5150)(11400 5150);
FORCEPROP 2 LAST SIG_NAME VR_PVNN_PCH_AIREF1
J 0
(10511 5157);
DISPLAY 0.617021 (10511 5157);
PAINT ORANGE (10511 5157);
WIRE 16 -1 (9125 3875)(9125 4075);
WIRE 16 -1 (9350 4075)(9125 4075);
WIRE 16 -1 (9125 4075)(9125 5150);
WIRE 16 -1 (10375 2275)(10375 2225);
WIRE 16 -1 (10375 2275)(11050 2275);
FORCEPROP 2 LAST SIG_NAME VR_P1V05_PCH_STBY_PH1_PHASE_SW
J 0
(10365 2285);
DISPLAY 0.617021 (10365 2285);
PAINT ORANGE (10365 2285);
FORCEPROP 2 LASTPROP $XRERR UNIQUE?
J 0
(10125 2285);
DISPLAY 0.638298 (10125 2285);
PAINT MONO (10125 2285);
DISPLAY INVISIBLE (10125 2285);
WIRE 16 -1 (11050 2250)(11050 2275);
WIRE 16 -1 (11050 2275)(11250 2275);
WIRE 16 -1 (10350 3975)(10550 3975);
FORCEPROP 2 LAST SIG_NAME VR_PVNN_PCH_PH1_PHASE_SW
J 0
(10440 3985);
DISPLAY 0.617021 (10440 3985);
PAINT ORANGE (10440 3985);
FORCEPROP 2 LASTPROP $XRERR UNIQUE?
J 0
(10200 3985);
DISPLAY 0.638298 (10200 3985);
PAINT MONO (10200 3985);
DISPLAY INVISIBLE (10200 3985);
WIRE 16 -1 (10550 3950)(10550 3975);
WIRE 16 -1 (11225 3975)(10550 3975);
WIRE 3 682 (7675 2625)(7575 2625);
WIRE 3 682 (7675 2900)(7675 2625);
WIRE 3 682 (7575 2625)(7575 2900);
WIRE 3 682 (7575 2900)(7675 2900);
WIRE 16 -1 (7175 3300)(7225 3300);
WIRE 16 -1 (7175 2900)(7175 3075);
WIRE 16 -1 (7175 3075)(7175 3300);
FORCEPROP 2 LAST SIG_NAME VR_P1V05_PCH_STBY_PH1_VCIN
J 0
(7215 3085);
DISPLAY 0.617021 (7215 3085);
PAINT ORANGE (7215 3085);
FORCEPROP 2 LASTPROP $XRERR UNIQUE?
J 0
(6975 3085);
DISPLAY 0.638298 (6975 3085);
PAINT MONO (6975 3085);
DISPLAY INVISIBLE (6975 3085);
WIRE 16 -1 (7175 3075)(9375 3075);
WIRE 3 2175 (7150 3400)(7150 3150);
WIRE 3 2175 (7150 3150)(7500 3150);
WIRE 3 2175 (7150 3400)(7500 3400);
WIRE 3 2175 (7500 3400)(7500 3150);
WIRE 16 2175 (7575 4775)(8250 4775);
WIRE 16 2175 (8250 4775)(8250 4275);
WIRE 16 2175 (7575 4775)(7575 4275);
WIRE 16 2175 (7575 4275)(8250 4275);
WIRE 16 -1 (7300 5050)(7325 5050);
WIRE 16 -1 (7300 4600)(7300 4825);
WIRE 16 -1 (7300 4825)(7300 5050);
FORCEPROP 2 LAST SIG_NAME VR_PVNN_PCH_PH1_VCIN
J 0
(7340 4835);
DISPLAY 0.617021 (7340 4835);
PAINT ORANGE (7340 4835);
FORCEPROP 2 LASTPROP $XRERR UNIQUE?
J 0
(7100 4835);
DISPLAY 0.638298 (7100 4835);
PAINT MONO (7100 4835);
DISPLAY INVISIBLE (7100 4835);
WIRE 16 -1 (7300 4825)(9350 4825);
WIRE 3 2175 (7250 4900)(7600 4900);
WIRE 3 2175 (7600 5150)(7600 4900);
WIRE 3 2175 (7250 5150)(7250 4900);
WIRE 3 2175 (7250 5150)(7600 5150);
WIRE 3 2175 (10450 1300)(13050 1300);
WIRE 3 2175 (13050 1300)(13050 650);
WIRE 3 2175 (10450 1300)(10450 650);
WIRE 3 2175 (10450 650)(13050 650);
WIRE 68 -1 (10500 1250)(11700 1250);
WIRE 68 -1 (11700 700)(11700 1250);
WIRE 68 -1 (10500 700)(10500 1250);
WIRE 68 -1 (10500 700)(11700 700);
WIRE 16 -1 (8850 900)(8900 900);
WIRE 16 -1 (9000 1400)(9100 1400);
WIRE 16 -1 (8900 900)(8900 1175);
WIRE 16 -1 (8825 1175)(8900 1175);
WIRE 16 -1 (8900 1175)(9000 1175);
WIRE 16 -1 (9000 1175)(9000 1400);
WIRE 16 -1 (10100 1175)(9000 1175);
FORCEPROP 0 LAST SIG_NAME VSENSE_PVNN_PCH_STBY_AVSP
J 0
(9365 1185);
DISPLAY 0.617021 (9365 1185);
PAINT ORANGE (9365 1185);
WIRE 16 -1 (9300 950)(10100 950);
FORCEPROP 0 LAST SIG_NAME VSENSE_PVNN_PCH_STBY_AVSN
J 0
(9365 960);
DISPLAY 0.617021 (9365 960);
PAINT ORANGE (9365 960);
WIRE 16 682 (8500 1350)(8500 775);
WIRE 16 682 (8900 1350)(8500 1350);
WIRE 16 682 (8500 775)(10050 775);
WIRE 16 682 (10050 775)(10050 1550);
WIRE 16 682 (8900 1550)(8900 1350);
WIRE 16 682 (8900 1550)(10050 1550);
WIRE 16 -1 (8625 1175)(7950 1175);
FORCEPROP 0 LAST SIG_NAME VSENSE_PVNN_PCH_STBY_QAT
J 0
(7940 1185);
DISPLAY 0.617021 (7940 1185);
PAINT ORANGE (7940 1185);
WIRE 16 -1 (10550 3675)(10550 3700);
WIRE 16 -1 (10550 3700)(10550 3750);
WIRE 16 -1 (10550 3700)(11250 3700);
FORCEPROP 2 LAST SIG_NAME VR_PVNN_PCH_PH1_PHASE_SW_RC
J 0
(10615 3710);
DISPLAY 0.510638 (10615 3710);
PAINT ORANGE (10615 3710);
FORCEPROP 2 LASTPROP $XRERR UNIQUE?
J 0
(11280 3700);
DISPLAY 0.638298 (11280 3700);
PAINT MONO (11280 3700);
DISPLAY INVISIBLE (11280 3700);
WIRE 16 -1 (10375 3075)(11400 3075);
FORCEPROP 2 LAST SIG_NAME ISENSE_P1V05_PCH_STBY_PH1_IMON
J 0
(10525 3089);
DISPLAY 0.617021 (10525 3089);
PAINT ORANGE (10525 3089);
WIRE 16 -1 (11050 2000)(10500 2000);
FORCEPROP 2 LAST SIG_NAME VR_P1V05_PCH_STBY_PH1_SW_RC
J 0
(10490 2010);
DISPLAY 0.510638 (10490 2010);
PAINT ORANGE (10490 2010);
FORCEPROP 2 LASTPROP $XRERR UNIQUE?
J 0
(10260 2000);
DISPLAY 0.638298 (10260 2000);
PAINT MONO (10260 2000);
DISPLAY INVISIBLE (10260 2000);
WIRE 16 -1 (11050 2000)(11050 1975);
WIRE 16 -1 (11050 2050)(11050 2000);
WIRE 16 -1 (9125 2125)(9125 2325);
WIRE 16 -1 (9375 2325)(9125 2325);
WIRE 16 -1 (9125 2325)(9125 3250);
WIRE 16 -1 (9125 3250)(12050 3250);
FORCEPROP 2 LAST SIG_NAME VR_P1V05_PCH_BIREF1
J 2
(12110 3261);
DISPLAY 0.617021 (12110 3261);
PAINT ORANGE (12110 3261);
WIRE 3 2175 (7800 2125)(8250 2125);
WIRE 3 2175 (8250 2400)(8250 2125);
WIRE 3 2175 (7800 2400)(7800 2125);
WIRE 3 2175 (7800 2400)(8250 2400);
WIRE 16 -1 (7950 900)(8650 900);
FORCEPROP 0 LAST SIG_NAME VSENSE_PVNN_PCH_STBY_FPK
J 0
(7965 910);
DISPLAY 0.617021 (7965 910);
PAINT ORANGE (7965 910);
WIRE 3 2175 (8875 1725)(9475 1725);
WIRE 3 2175 (9475 2300)(9475 1725);
WIRE 3 2175 (8875 2300)(8875 1725);
WIRE 3 2175 (8875 2300)(9475 2300);
WIRE 16 -1 (9350 4275)(8450 4275);
FORCEPROP 0 LAST SIG_NAME TP_PVNN_PCH_GL_0
J 0
(8465 4285);
DISPLAY 0.617021 (8465 4285);
PAINT ORANGE (8465 4285);
FORCEPROP 2 LASTPROP $XRERR UNIQUE?
J 0
(8210 4275);
DISPLAY 0.638298 (8210 4275);
PAINT MONO (8210 4275);
DISPLAY INVISIBLE (8210 4275);
WIRE 16 -1 (9350 4325)(8450 4325);
FORCEPROP 0 LAST SIG_NAME TP_PVNN_PCH_GL_1
J 0
(8465 4335);
DISPLAY 0.617021 (8465 4335);
PAINT ORANGE (8465 4335);
FORCEPROP 2 LASTPROP $XRERR UNIQUE?
J 0
(8210 4325);
DISPLAY 0.638298 (8210 4325);
PAINT MONO (8210 4325);
DISPLAY INVISIBLE (8210 4325);
WIRE 3 2175 (10850 4100)(11325 4100);
WIRE 3 2175 (11325 4425)(11325 4100);
WIRE 3 2175 (10850 4425)(10850 4100);
WIRE 3 2175 (10850 4425)(11325 4425);
WIRE 16 -1 (6975 3950)(6975 4050);
WIRE 16 -1 (7925 4050)(6975 4050);
FORCEPROP 0 LAST SIG_NAME VR_PVNN_PCH_PH1_BOOT
J 0
(7040 4060);
DISPLAY 0.617021 (7040 4060);
PAINT ORANGE (7040 4060);
FORCEPROP 2 LASTPROP $XRERR UNIQUE?
J 0
(6800 4060);
DISPLAY 0.638298 (6800 4060);
PAINT MONO (6800 4060);
DISPLAY INVISIBLE (6800 4060);
WIRE 16 -1 (10350 4825)(11275 4825);
FORCEPROP 2 LAST SIG_NAME ISENSE_PVNN_PCH_PH1_IMON
J 2
(11050 4839);
DISPLAY 0.617021 (11050 4839);
PAINT ORANGE (11050 4839);
WIRE 3 682 (10450 2825)(10550 2825);
WIRE 16 -1 (7050 2200)(7050 2325);
WIRE 16 -1 (7950 2325)(7050 2325);
FORCEPROP 0 LAST SIG_NAME VR_P1V05_PCH_STBY_PH1_BOOT
J 0
(7115 2335);
DISPLAY 0.617021 (7115 2335);
PAINT ORANGE (7115 2335);
FORCEPROP 2 LASTPROP $XRERR UNIQUE?
J 0
(6875 2335);
DISPLAY 0.638298 (6875 2335);
PAINT MONO (6875 2335);
DISPLAY INVISIBLE (6875 2335);
WIRE 16 -1 (6875 1275)(6300 1275);
FORCEPROP 0 LAST SIG_NAME VSENSE_P1V05_PCH_STBY_AVSP
J 0
(6290 1285);
DISPLAY 0.617021 (6290 1285);
PAINT ORANGE (6290 1285);
WIRE 16 -1 (6875 1150)(6875 1275);
WIRE 16 -1 (7000 1150)(6875 1150);
WIRE 16 -1 (7175 1150)(7175 1300);
WIRE 16 -1 (7350 1300)(7175 1300);
WIRE 16 -1 (7000 1300)(7000 1150);
WIRE 16 -1 (7000 1300)(7175 1300);
WIRE 16 -1 (7175 950)(7175 850);
WIRE 16 -1 (7325 850)(7175 850);
WIRE 16 -1 (7000 850)(7175 850);
WIRE 16 -1 (7000 1075)(7000 850);
WIRE 16 -1 (6875 1075)(7000 1075);
WIRE 16 -1 (6875 950)(6875 1075);
WIRE 16 -1 (6275 950)(6875 950);
FORCEPROP 0 LAST SIG_NAME VSENSE_P1V05_PCH_STBY_AVSN
J 0
(6265 960);
DISPLAY 0.617021 (6265 960);
PAINT ORANGE (6265 960);
WIRE 16 -1 (9375 2575)(8475 2575);
FORCEPROP 0 LAST SIG_NAME TP_P1V05_PCH_GL_1
J 0
(8490 2585);
DISPLAY 0.617021 (8490 2585);
PAINT ORANGE (8490 2585);
FORCEPROP 2 LASTPROP $XRERR UNIQUE?
J 0
(8235 2575);
DISPLAY 0.638298 (8235 2575);
PAINT MONO (8235 2575);
DISPLAY INVISIBLE (8235 2575);
DOT 1 (6000 4250);
DOT 1 (6250 3025);
DOT 1 (6475 3025);
DOT 1 (6700 3025);
DOT 1 (7625 2500);
DOT 1 (7625 3300);
DOT 1 (7800 4250);
DOT 1 (7800 5050);
DOT 1 (11650 2275);
DOT 1 (11725 3975);
DOT 1 (12175 2275);
DOT 1 (10450 2075);
DOT 1 (11925 2275);
DOT 1 (9225 4625);
DOT 1 (10925 4450);
DOT 1 (12025 3975);
DOT 1 (12325 3600);
DOT 1 (12650 3975);
DOT 1 (10550 3700);
DOT 1 (10550 3975);
DOT 1 (7025 4725);
DOT 1 (7025 4250);
DOT 1 (6775 4250);
DOT 1 (6775 4725);
DOT 1 (6525 4250);
DOT 1 (6525 4725);
DOT 1 (6275 4250);
DOT 1 (7300 4250);
DOT 1 (6475 2500);
DOT 1 (6250 2500);
DOT 1 (6700 2500);
DOT 1 (6925 2500);
DOT 1 (6925 3025);
DOT 1 (7175 2500);
DOT 1 (7175 3075);
DOT 1 (12175 1900);
DOT 1 (7175 1300);
DOT 1 (11650 1900);
DOT 1 (10450 1975);
DOT 1 (12600 3975);
DOT 1 (12600 3600);
DOT 1 (9050 4725);
DOT 1 (12025 3600);
DOT 1 (12425 2275);
DOT 1 (10450 3825);
DOT 1 (10450 3775);
DOT 1 (10450 3725);
DOT 1 (11050 2275);
DOT 1 (10900 2725);
DOT 1 (12425 1900);
DOT 1 (10450 2025);
DOT 1 (9125 4075);
DOT 1 (8525 3300);
DOT 1 (9200 3025);
DOT 1 (9125 2325);
DOT 1 (7300 4825);
DOT 1 (6275 4725);
DOT 1 (6025 2500);
DOT 1 (7175 850);
DOT 1 (11050 2000);
DOT 1 (9275 2875);
DOT 1 (11650 3975);
DOT 1 (11600 2275);
DOT 1 (11925 1900);
DOT 1 (12700 2275);
DOT 1 (12325 3975);
DOT 1 (8125 5050);
DOT 1 (8525 5050);
DOT 1 (8000 3300);
DOT 1 (8900 1175);
DOT 1 (9000 1175);
DOT 1 (10850 1200);
DOT 1 (11150 1200);
DOT 1 (11450 1200);
DOT 1 (11800 1200);
DOT 1 (12100 1200);
DOT 1 (12400 1200);
DOT 1 (12700 1200);
FORCENOTE
TP FAB1 DEL NET 0309
(10600 2825) 0;
DISPLAY LEFT (10600 2825);
DISPLAY 1.021277 (10600 2825);
PAINT RED (10600 2825);
FORCENOTE
SPOF
(6646 1726) 0;
DISPLAY LEFT (6646 1726);
DISPLAY 2.340426 (6646 1726);
PAINT PURPLE (6646 1726);
FORCENOTE
PLACE ON TOP
(7420 2500) 0;
DISPLAY LEFT (7420 2500);
DISPLAY 1.553191 (7420 2500);
PAINT PURPLE (7420 2500);
FORCENOTE
TP FAB1 CO-LAY WITH TI PARTS 11/16
(11475 1650) 0;
DISPLAY LEFT (11475 1650);
DISPLAY 0.851064 (11475 1650);
PAINT RED (11475 1650);
FORCENOTE
PLACE ON TOP
(7595 4175) 0;
DISPLAY LEFT (7595 4175);
DISPLAY 1.553191 (7595 4175);
PAINT PURPLE (7595 4175);
FORCENOTE
TDA21460
(9650 4900) 0;
DISPLAY LEFT (9650 4900);
DISPLAY 1.021277 (9650 4900);
PAINT PURPLE (9650 4900);
FORCENOTE
ROOM= PVNN_PCH_STBY
(9677 5006) 0;
DISPLAY LEFT (9677 5006);
DISPLAY 1.595745 (9677 5006);
PAINT PURPLE (9677 5006);
FORCENOTE
TDA21460
(9700 3150) 0;
DISPLAY LEFT (9700 3150);
DISPLAY 1.021277 (9700 3150);
PAINT SKYBLUE (9700 3150);
FORCENOTE
TP FAB1 ADD NET NAME 12/04
(10375 1775) 0;
DISPLAY LEFT (10375 1775);
DISPLAY 0.680851 (10375 1775);
PAINT RED (10375 1775);
FORCENOTE
TP FAB1 CHANGE RES TO 1 OHM 0603 0107
(9925 1575) 0;
DISPLAY LEFT (9925 1575);
DISPLAY 1.021277 (9925 1575);
PAINT RED (9925 1575);
FORCENOTE
TP FAB1 CHANGE PN 0310
(7625 3025) 0;
DISPLAY LEFT (7625 3025);
DISPLAY 1.021277 (7625 3025);
PAINT RED (7625 3025);
FORCENOTE
TP FAB1 CHANGE PN 0310
(7575 4775) 0;
DISPLAY LEFT (7575 4775);
DISPLAY 1.021277 (7575 4775);
PAINT RED (7575 4775);
FORCENOTE
TP FAB1 CHANGE L7A4 PN 0122
(11650 2300) 0;
DISPLAY LEFT (11650 2300);
DISPLAY 1.021277 (11650 2300);
PAINT RED (11650 2300);
FORCENOTE
TP FAB1 CO-LAY WITH TI PARTS 11/16
(11075 2525) 0;
DISPLAY LEFT (11075 2525);
DISPLAY 0.851064 (11075 2525);
PAINT RED (11075 2525);
FORCENOTE
TP FAB1 ADD NET NAME 12/04
(11225 3500) 0;
DISPLAY LEFT (11225 3500);
DISPLAY 0.680851 (11225 3500);
PAINT RED (11225 3500);
FORCENOTE
TP FAB1 CO-LAY WITH TI PARTS 11/16
(11375 4150) 0;
DISPLAY LEFT (11375 4150);
DISPLAY 0.851064 (11375 4150);
PAINT RED (11375 4150);
FORCENOTE
TP FAB1 CHANGE L7A2 PN 0122
(11350 4075) 0;
DISPLAY LEFT (11350 4075);
DISPLAY 1.021277 (11350 4075);
PAINT RED (11350 4075);
FORCENOTE
P1V05_PCH_STBY_VOLTAGE SENSE
(5805 755) 0;
DISPLAY LEFT (5805 755);
PAINT PURPLE (5805 755);
FORCENOTE
ROUTE AS DIFF PAIR
(6630 1080) 0;
DISPLAY LEFT (6630 1080);
DISPLAY 0.808511 (6630 1080);
PAINT PURPLE (6630 1080);
FORCENOTE
5MIL SPACING
(6555 855) 0;
DISPLAY LEFT (6555 855);
DISPLAY 0.808511 (6555 855);
PAINT PURPLE (6555 855);
FORCENOTE
10MIL WIDTH
(6555 905) 0;
DISPLAY LEFT (6555 905);
DISPLAY 0.808511 (6555 905);
PAINT PURPLE (6555 905);
FORCENOTE
TP FAB1 CO-LAY WITH TI PARTS 11/16
(7775 3600) 0;
DISPLAY LEFT (7775 3600);
DISPLAY 0.851064 (7775 3600);
PAINT RED (7775 3600);
FORCENOTE
TP FAB1 CHANGE TO 0 OHM 0107
(7250 5150) 0;
DISPLAY LEFT (7250 5150);
DISPLAY 0.638298 (7250 5150);
PAINT RED (7250 5150);
FORCENOTE
TP FAB1 CHANGE TO 0 OHM 0107
(7100 3400) 0;
DISPLAY LEFT (7100 3400);
DISPLAY 0.638298 (7100 3400);
PAINT RED (7100 3400);
FORCENOTE
TP FAB1 DEL NET 0309
(10625 4550) 0;
DISPLAY LEFT (10625 4550);
DISPLAY 1.021277 (10625 4550);
PAINT RED (10625 4550);
FORCENOTE
PVNN_PCH_STBY_VOLTAGE SENSE
(8155 605) 0;
DISPLAY LEFT (8155 605);
PAINT PURPLE (8155 605);
FORCENOTE
ROOM= P1V05_PCH_STBY_VR
(7602 1631) 0;
DISPLAY LEFT (7602 1631);
DISPLAY 1.595745 (7602 1631);
PAINT PURPLE (7602 1631);
FORCENOTE
TP FAB1 CO-LAY WITH TI PARTS 11/16
(7775 1800) 0;
DISPLAY LEFT (7775 1800);
DISPLAY 0.851064 (7775 1800);
PAINT RED (7775 1800);
FORCENOTE
TP FAB1 CO-LAY WITH TI PARTS 11/16
(11175 3425) 0;
DISPLAY LEFT (11175 3425);
DISPLAY 0.851064 (11175 3425);
PAINT RED (11175 3425);
FORCENOTE
TP FAB1 CHANGE RES TO 1 OHM 0603 0107
(10500 3275) 0;
DISPLAY LEFT (10500 3275);
DISPLAY 1.021277 (10500 3275);
PAINT RED (10500 3275);
FORCENOTE
TP FAB1 CHANGE ONE 100UF CPA TO FOUR 22UF CAPS 0107
(10750 575) 0;
DISPLAY LEFT (10750 575);
DISPLAY 1.021277 (10750 575);
PAINT RED (10750 575);
FORCENOTE
PLACE NEAR PCH EDGE
(7780 1030) 0;
DISPLAY LEFT (7780 1030);
DISPLAY 0.808511 (7780 1030);
PAINT PURPLE (7780 1030);
FORCENOTE
PCH SIDE
(7955 1105) 0;
DISPLAY LEFT (7955 1105);
PAINT PURPLE (7955 1105);
FORCENOTE
SPOF
(8521 1376) 0;
DISPLAY LEFT (8521 1376);
DISPLAY 1.489362 (8521 1376);
PAINT PURPLE (8521 1376);
FORCENOTE
VR CONTROLLER SIDE
(9355 1055) 0;
DISPLAY LEFT (9355 1055);
PAINT PURPLE (9355 1055);
FORCENOTE
PUT TOGETHER
(11750 1250) 0;
DISPLAY LEFT (11750 1250);
DISPLAY 0.808511 (11750 1250);
PAINT PURPLE (11750 1250);
FORCENOTE
PUT TOGETHER
(10500 1250) 0;
DISPLAY LEFT (10500 1250);
DISPLAY 0.808511 (10500 1250);
PAINT PURPLE (10500 1250);
FORCENOTE
SPOF
(7246 3476) 0;
DISPLAY LEFT (7246 3476);
DISPLAY 2.340426 (7246 3476);
PAINT PURPLE (7246 3476);
QUIT
